FILE_TYPE = MACRO_DRAWING;
SET COLOR_WIRE YELLOW;
SET COLOR_PROP ORANGE;
SET COLOR_DOT WHITE;
SET COLOR_ARC YELLOW;
SET COLOR_BODY GREEN;
SET COLOR_NOTE PURPLE;
SET PROP_DISPLAY VALUE;
SET PAGE_NUMBER P91;
FORCEADD UNIVERSAL_GND..1
(-1650 -250);
FORCEPROP 3 LASTPIN (-1650 -200) SIG_NAME GND\g
J 0
(-1640 -190);
DISPLAY 0.659574 (-1640 -190);
PAINT MONO (-1640 -190);
DISPLAY INVISIBLE (-1640 -190);
FORCEPROP 2 LAST CDS_LIB logical_power
J 0
(-1650 -250);
PAINT MONO (-1650 -250);
DISPLAY INVISIBLE (-1650 -250);
FORCEPROP 1 LAST HDL_POWER GND
J 1
(-1625 -325);
DISPLAY 0.872340 (-1625 -325);
PAINT GREEN (-1625 -325);
DISPLAY INVISIBLE (-1625 -325);
FORCEPROP 1 LAST PATH I1
J 0
(-1575 -250);
DISPLAY 0.872340 (-1575 -250);
PAINT AQUA (-1575 -250);
DISPLAY INVISIBLE (-1575 -250);
FORCEADD OFFPAGE..1
(-2800 1875);
FORCEPROP 2 LAST $XR3 93 
J 0
(-3052 1839);
DISPLAY 0.638298 (-3052 1839);
PAINT MONO (-3052 1839);
FORCEPROP 2 LAST $XR2 92 
J 0
(-3232 1875);
DISPLAY 0.638298 (-3232 1875);
PAINT MONO (-3232 1875);
FORCEPROP 2 LAST $XR1 90 
J 0
(-3142 1875);
DISPLAY 0.638298 (-3142 1875);
PAINT MONO (-3142 1875);
FORCEPROP 2 LAST $XR0 129 
J 0
(-3052 1875);
DISPLAY 0.638298 (-3052 1875);
PAINT MONO (-3052 1875);
FORCEPROP 2 LAST CDS_LIB standard
J 0
(-2800 1875);
PAINT MONO (-2800 1875);
DISPLAY INVISIBLE (-2800 1875);
FORCEPROP 1 LAST OFFPAGE TRUE
J 0
(-2475 1750);
DISPLAY 0.872340 (-2475 1750);
DISPLAY INVISIBLE (-2475 1750);
FORCEPROP 1 LAST COMMENT_BODY TRUE
J 0
(-2675 1775);
DISPLAY 0.872340 (-2675 1775);
PAINT GREEN (-2675 1775);
DISPLAY INVISIBLE (-2675 1775);
FORCEPROP 2 LAST PATH I10
J 0
(-2750 1950);
DISPLAY 1.021277 (-2750 1950);
DISPLAY INVISIBLE (-2750 1950);
FORCEADD TAP..1
(-225 3325);
FORCEPROP 3 LASTPIN (-275 3325) SIG_NAME M_E_CPU0_SA_DQ<15>
J 0
(-265 3335);
DISPLAY 0.659574 (-265 3335);
PAINT MONO (-265 3335);
DISPLAY INVISIBLE (-265 3335);
FORCEPROP 1 LASTPIN (-275 3325) BN 15
J 0
(-287 3333);
DISPLAY 0.680851 (-287 3333);
PAINT GREEN (-287 3333);
FORCEPROP 2 LAST CDS_LIB standard
J 0
(-225 3325);
PAINT MONO (-225 3325);
DISPLAY INVISIBLE (-225 3325);
FORCEPROP 1 LAST BODY_TYPE PLUMBING
J 0
(-225 3375);
DISPLAY 0.872340 (-225 3375);
PAINT GREEN (-225 3375);
DISPLAY INVISIBLE (-225 3375);
FORCEPROP 1 LAST HDL_TAP TRUE
J 0
(100 3200);
DISPLAY 0.872340 (100 3200);
DISPLAY INVISIBLE (100 3200);
FORCEPROP 1 LAST PATH I100
J 0
(-227 3325);
DISPLAY 0.872340 (-227 3325);
PAINT GREEN (-227 3325);
DISPLAY INVISIBLE (-227 3325);
FORCEADD TAP..1
(-225 3425);
FORCEPROP 3 LASTPIN (-275 3425) SIG_NAME M_E_CPU0_SA_DQ<17>
J 0
(-265 3435);
DISPLAY 0.659574 (-265 3435);
PAINT MONO (-265 3435);
DISPLAY INVISIBLE (-265 3435);
FORCEPROP 1 LASTPIN (-275 3425) BN 17
J 0
(-287 3433);
DISPLAY 0.680851 (-287 3433);
PAINT GREEN (-287 3433);
FORCEPROP 2 LAST CDS_LIB standard
J 0
(-225 3425);
PAINT MONO (-225 3425);
DISPLAY INVISIBLE (-225 3425);
FORCEPROP 1 LAST BODY_TYPE PLUMBING
J 0
(-225 3475);
DISPLAY 0.872340 (-225 3475);
PAINT GREEN (-225 3475);
DISPLAY INVISIBLE (-225 3475);
FORCEPROP 1 LAST HDL_TAP TRUE
J 0
(100 3300);
DISPLAY 0.872340 (100 3300);
DISPLAY INVISIBLE (100 3300);
FORCEPROP 1 LAST PATH I101
J 0
(-227 3425);
DISPLAY 0.872340 (-227 3425);
PAINT GREEN (-227 3425);
DISPLAY INVISIBLE (-227 3425);
FORCEADD TAP..1
(-225 3475);
FORCEPROP 3 LASTPIN (-275 3475) SIG_NAME M_E_CPU0_SA_DQ<18>
J 0
(-265 3485);
DISPLAY 0.659574 (-265 3485);
PAINT MONO (-265 3485);
DISPLAY INVISIBLE (-265 3485);
FORCEPROP 1 LASTPIN (-275 3475) BN 18
J 0
(-287 3483);
DISPLAY 0.680851 (-287 3483);
PAINT GREEN (-287 3483);
FORCEPROP 2 LAST CDS_LIB standard
J 0
(-225 3475);
PAINT MONO (-225 3475);
DISPLAY INVISIBLE (-225 3475);
FORCEPROP 1 LAST BODY_TYPE PLUMBING
J 0
(-225 3525);
DISPLAY 0.872340 (-225 3525);
PAINT GREEN (-225 3525);
DISPLAY INVISIBLE (-225 3525);
FORCEPROP 1 LAST HDL_TAP TRUE
J 0
(100 3350);
DISPLAY 0.872340 (100 3350);
DISPLAY INVISIBLE (100 3350);
FORCEPROP 1 LAST PATH I102
J 0
(-227 3475);
DISPLAY 0.872340 (-227 3475);
PAINT GREEN (-227 3475);
DISPLAY INVISIBLE (-227 3475);
FORCEADD TAP..1
(-225 3525);
FORCEPROP 3 LASTPIN (-275 3525) SIG_NAME M_E_CPU0_SA_DQ<19>
J 0
(-265 3535);
DISPLAY 0.659574 (-265 3535);
PAINT MONO (-265 3535);
DISPLAY INVISIBLE (-265 3535);
FORCEPROP 1 LASTPIN (-275 3525) BN 19
J 0
(-287 3533);
DISPLAY 0.680851 (-287 3533);
PAINT GREEN (-287 3533);
FORCEPROP 2 LAST CDS_LIB standard
J 0
(-225 3525);
PAINT MONO (-225 3525);
DISPLAY INVISIBLE (-225 3525);
FORCEPROP 1 LAST BODY_TYPE PLUMBING
J 0
(-225 3575);
DISPLAY 0.872340 (-225 3575);
PAINT GREEN (-225 3575);
DISPLAY INVISIBLE (-225 3575);
FORCEPROP 1 LAST HDL_TAP TRUE
J 0
(100 3400);
DISPLAY 0.872340 (100 3400);
DISPLAY INVISIBLE (100 3400);
FORCEPROP 1 LAST PATH I103
J 0
(-227 3525);
DISPLAY 0.872340 (-227 3525);
PAINT GREEN (-227 3525);
DISPLAY INVISIBLE (-227 3525);
FORCEADD TAP..1
(-225 3575);
FORCEPROP 3 LASTPIN (-275 3575) SIG_NAME M_E_CPU0_SA_DQ<20>
J 0
(-265 3585);
DISPLAY 0.659574 (-265 3585);
PAINT MONO (-265 3585);
DISPLAY INVISIBLE (-265 3585);
FORCEPROP 1 LASTPIN (-275 3575) BN 20
J 0
(-287 3583);
DISPLAY 0.680851 (-287 3583);
PAINT GREEN (-287 3583);
FORCEPROP 2 LAST CDS_LIB standard
J 0
(-225 3575);
PAINT MONO (-225 3575);
DISPLAY INVISIBLE (-225 3575);
FORCEPROP 1 LAST BODY_TYPE PLUMBING
J 0
(-225 3625);
DISPLAY 0.872340 (-225 3625);
PAINT GREEN (-225 3625);
DISPLAY INVISIBLE (-225 3625);
FORCEPROP 1 LAST HDL_TAP TRUE
J 0
(100 3450);
DISPLAY 0.872340 (100 3450);
DISPLAY INVISIBLE (100 3450);
FORCEPROP 1 LAST PATH I104
J 0
(-227 3575);
DISPLAY 0.872340 (-227 3575);
PAINT GREEN (-227 3575);
DISPLAY INVISIBLE (-227 3575);
FORCEADD TAP..1
(-225 3625);
FORCEPROP 3 LASTPIN (-275 3625) SIG_NAME M_E_CPU0_SA_DQ<21>
J 0
(-265 3635);
DISPLAY 0.659574 (-265 3635);
PAINT MONO (-265 3635);
DISPLAY INVISIBLE (-265 3635);
FORCEPROP 1 LASTPIN (-275 3625) BN 21
J 0
(-287 3633);
DISPLAY 0.680851 (-287 3633);
PAINT GREEN (-287 3633);
FORCEPROP 2 LAST CDS_LIB standard
J 0
(-225 3625);
PAINT MONO (-225 3625);
DISPLAY INVISIBLE (-225 3625);
FORCEPROP 1 LAST BODY_TYPE PLUMBING
J 0
(-225 3675);
DISPLAY 0.872340 (-225 3675);
PAINT GREEN (-225 3675);
DISPLAY INVISIBLE (-225 3675);
FORCEPROP 1 LAST HDL_TAP TRUE
J 0
(100 3500);
DISPLAY 0.872340 (100 3500);
DISPLAY INVISIBLE (100 3500);
FORCEPROP 1 LAST PATH I105
J 0
(-227 3625);
DISPLAY 0.872340 (-227 3625);
PAINT GREEN (-227 3625);
DISPLAY INVISIBLE (-227 3625);
FORCEADD TAP..1
(-225 3675);
FORCEPROP 3 LASTPIN (-275 3675) SIG_NAME M_E_CPU0_SA_DQ<22>
J 0
(-265 3685);
DISPLAY 0.659574 (-265 3685);
PAINT MONO (-265 3685);
DISPLAY INVISIBLE (-265 3685);
FORCEPROP 1 LASTPIN (-275 3675) BN 22
J 0
(-287 3683);
DISPLAY 0.680851 (-287 3683);
PAINT GREEN (-287 3683);
FORCEPROP 2 LAST CDS_LIB standard
J 0
(-225 3675);
DISPLAY INVISIBLE (-225 3675);
FORCEPROP 1 LAST BODY_TYPE PLUMBING
J 0
(-225 3725);
DISPLAY 0.872340 (-225 3725);
PAINT GREEN (-225 3725);
DISPLAY INVISIBLE (-225 3725);
FORCEPROP 1 LAST HDL_TAP TRUE
J 0
(100 3550);
DISPLAY 0.872340 (100 3550);
DISPLAY INVISIBLE (100 3550);
FORCEPROP 1 LAST PATH I106
J 0
(-227 3675);
DISPLAY 0.872340 (-227 3675);
PAINT GREEN (-227 3675);
DISPLAY INVISIBLE (-227 3675);
FORCEADD TAP..1
(-225 3725);
FORCEPROP 3 LASTPIN (-275 3725) SIG_NAME M_E_CPU0_SA_DQ<23>
J 0
(-265 3735);
DISPLAY 0.659574 (-265 3735);
PAINT MONO (-265 3735);
DISPLAY INVISIBLE (-265 3735);
FORCEPROP 1 LASTPIN (-275 3725) BN 23
J 0
(-287 3733);
DISPLAY 0.680851 (-287 3733);
PAINT GREEN (-287 3733);
FORCEPROP 2 LAST CDS_LIB standard
J 0
(-225 3725);
DISPLAY INVISIBLE (-225 3725);
FORCEPROP 1 LAST BODY_TYPE PLUMBING
J 0
(-225 3775);
DISPLAY 0.872340 (-225 3775);
PAINT GREEN (-225 3775);
DISPLAY INVISIBLE (-225 3775);
FORCEPROP 1 LAST HDL_TAP TRUE
J 0
(100 3600);
DISPLAY 0.872340 (100 3600);
DISPLAY INVISIBLE (100 3600);
FORCEPROP 1 LAST PATH I107
J 0
(-227 3725);
DISPLAY 0.872340 (-227 3725);
PAINT GREEN (-227 3725);
DISPLAY INVISIBLE (-227 3725);
FORCEADD TAP..1
(-225 3825);
FORCEPROP 3 LASTPIN (-275 3825) SIG_NAME M_E_CPU0_SA_DQ<25>
J 0
(-265 3835);
DISPLAY 0.659574 (-265 3835);
PAINT MONO (-265 3835);
DISPLAY INVISIBLE (-265 3835);
FORCEPROP 1 LASTPIN (-275 3825) BN 25
J 0
(-287 3833);
DISPLAY 0.680851 (-287 3833);
PAINT GREEN (-287 3833);
FORCEPROP 2 LAST CDS_LIB standard
J 0
(-225 3825);
DISPLAY INVISIBLE (-225 3825);
FORCEPROP 1 LAST BODY_TYPE PLUMBING
J 0
(-225 3875);
DISPLAY 0.872340 (-225 3875);
PAINT GREEN (-225 3875);
DISPLAY INVISIBLE (-225 3875);
FORCEPROP 1 LAST HDL_TAP TRUE
J 0
(100 3700);
DISPLAY 0.872340 (100 3700);
DISPLAY INVISIBLE (100 3700);
FORCEPROP 1 LAST PATH I108
J 0
(-227 3825);
DISPLAY 0.872340 (-227 3825);
PAINT GREEN (-227 3825);
DISPLAY INVISIBLE (-227 3825);
FORCEADD TAP..1
(-225 3775);
FORCEPROP 3 LASTPIN (-275 3775) SIG_NAME M_E_CPU0_SA_DQ<24>
J 0
(-265 3785);
DISPLAY 0.659574 (-265 3785);
PAINT MONO (-265 3785);
DISPLAY INVISIBLE (-265 3785);
FORCEPROP 1 LASTPIN (-275 3775) BN 24
J 0
(-287 3783);
DISPLAY 0.680851 (-287 3783);
PAINT GREEN (-287 3783);
FORCEPROP 2 LAST CDS_LIB standard
J 0
(-225 3775);
DISPLAY INVISIBLE (-225 3775);
FORCEPROP 1 LAST BODY_TYPE PLUMBING
J 0
(-225 3825);
DISPLAY 0.872340 (-225 3825);
PAINT GREEN (-225 3825);
DISPLAY INVISIBLE (-225 3825);
FORCEPROP 1 LAST HDL_TAP TRUE
J 0
(100 3650);
DISPLAY 0.872340 (100 3650);
DISPLAY INVISIBLE (100 3650);
FORCEPROP 1 LAST PATH I109
J 0
(-227 3775);
DISPLAY 0.872340 (-227 3775);
PAINT GREEN (-227 3775);
DISPLAY INVISIBLE (-227 3775);
FORCEADD OFFPAGE..1
(-2800 1775);
FORCEPROP 2 LAST $XR1 90 
J 0
(-3111 1775);
DISPLAY 0.638298 (-3111 1775);
PAINT MONO (-3111 1775);
FORCEPROP 2 LAST $XR0 24 
J 0
(-3021 1775);
DISPLAY 0.638298 (-3021 1775);
PAINT MONO (-3021 1775);
FORCEPROP 2 LAST CDS_LIB standard
J 0
(-2800 1775);
PAINT MONO (-2800 1775);
DISPLAY INVISIBLE (-2800 1775);
FORCEPROP 1 LAST OFFPAGE TRUE
J 0
(-2475 1650);
DISPLAY 0.872340 (-2475 1650);
DISPLAY INVISIBLE (-2475 1650);
FORCEPROP 1 LAST COMMENT_BODY TRUE
J 0
(-2675 1675);
DISPLAY 0.872340 (-2675 1675);
PAINT GREEN (-2675 1675);
DISPLAY INVISIBLE (-2675 1675);
FORCEPROP 2 LAST PATH I11
J 0
(-2750 1850);
DISPLAY 1.021277 (-2750 1850);
DISPLAY INVISIBLE (-2750 1850);
FORCEADD TAP..1
(-225 3875);
FORCEPROP 3 LASTPIN (-275 3875) SIG_NAME M_E_CPU0_SA_DQ<26>
J 0
(-265 3885);
DISPLAY 0.659574 (-265 3885);
PAINT MONO (-265 3885);
DISPLAY INVISIBLE (-265 3885);
FORCEPROP 1 LASTPIN (-275 3875) BN 26
J 0
(-287 3883);
DISPLAY 0.680851 (-287 3883);
PAINT GREEN (-287 3883);
FORCEPROP 2 LAST CDS_LIB standard
J 0
(-225 3875);
DISPLAY INVISIBLE (-225 3875);
FORCEPROP 1 LAST BODY_TYPE PLUMBING
J 0
(-225 3925);
DISPLAY 0.872340 (-225 3925);
PAINT GREEN (-225 3925);
DISPLAY INVISIBLE (-225 3925);
FORCEPROP 1 LAST HDL_TAP TRUE
J 0
(100 3750);
DISPLAY 0.872340 (100 3750);
DISPLAY INVISIBLE (100 3750);
FORCEPROP 1 LAST PATH I110
J 0
(-227 3875);
DISPLAY 0.872340 (-227 3875);
PAINT GREEN (-227 3875);
DISPLAY INVISIBLE (-227 3875);
FORCEADD TAP..1
(-225 3925);
FORCEPROP 3 LASTPIN (-275 3925) SIG_NAME M_E_CPU0_SA_DQ<27>
J 0
(-265 3935);
DISPLAY 0.659574 (-265 3935);
PAINT MONO (-265 3935);
DISPLAY INVISIBLE (-265 3935);
FORCEPROP 1 LASTPIN (-275 3925) BN 27
J 0
(-287 3933);
DISPLAY 0.680851 (-287 3933);
PAINT GREEN (-287 3933);
FORCEPROP 2 LAST CDS_LIB standard
J 0
(-225 3925);
DISPLAY INVISIBLE (-225 3925);
FORCEPROP 1 LAST BODY_TYPE PLUMBING
J 0
(-225 3975);
DISPLAY 0.872340 (-225 3975);
PAINT GREEN (-225 3975);
DISPLAY INVISIBLE (-225 3975);
FORCEPROP 1 LAST HDL_TAP TRUE
J 0
(100 3800);
DISPLAY 0.872340 (100 3800);
DISPLAY INVISIBLE (100 3800);
FORCEPROP 1 LAST PATH I111
J 0
(-227 3925);
DISPLAY 0.872340 (-227 3925);
PAINT GREEN (-227 3925);
DISPLAY INVISIBLE (-227 3925);
FORCEADD TAP..1
(-225 3975);
FORCEPROP 3 LASTPIN (-275 3975) SIG_NAME M_E_CPU0_SA_DQ<28>
J 0
(-265 3985);
DISPLAY 0.659574 (-265 3985);
PAINT MONO (-265 3985);
DISPLAY INVISIBLE (-265 3985);
FORCEPROP 1 LASTPIN (-275 3975) BN 28
J 0
(-287 3983);
DISPLAY 0.680851 (-287 3983);
PAINT GREEN (-287 3983);
FORCEPROP 2 LAST CDS_LIB standard
J 0
(-225 3975);
DISPLAY INVISIBLE (-225 3975);
FORCEPROP 1 LAST BODY_TYPE PLUMBING
J 0
(-225 4025);
DISPLAY 0.872340 (-225 4025);
PAINT GREEN (-225 4025);
DISPLAY INVISIBLE (-225 4025);
FORCEPROP 1 LAST HDL_TAP TRUE
J 0
(100 3850);
DISPLAY 0.872340 (100 3850);
DISPLAY INVISIBLE (100 3850);
FORCEPROP 1 LAST PATH I112
J 0
(-227 3975);
DISPLAY 0.872340 (-227 3975);
PAINT GREEN (-227 3975);
DISPLAY INVISIBLE (-227 3975);
FORCEADD OFFPAGE..1
(-2800 4150);
FORCEPROP 2 LAST $XR1 90 
J 0
(-3111 4150);
DISPLAY 0.638298 (-3111 4150);
PAINT MONO (-3111 4150);
FORCEPROP 2 LAST $XR0 24 
J 0
(-3021 4150);
DISPLAY 0.638298 (-3021 4150);
PAINT MONO (-3021 4150);
FORCEPROP 2 LAST CDS_LIB standard
J 0
(-2800 4150);
PAINT MONO (-2800 4150);
DISPLAY INVISIBLE (-2800 4150);
FORCEPROP 1 LAST OFFPAGE TRUE
J 0
(-2475 4025);
DISPLAY 0.872340 (-2475 4025);
DISPLAY INVISIBLE (-2475 4025);
FORCEPROP 1 LAST COMMENT_BODY TRUE
J 0
(-2675 4050);
DISPLAY 0.872340 (-2675 4050);
PAINT GREEN (-2675 4050);
DISPLAY INVISIBLE (-2675 4050);
FORCEPROP 2 LAST PATH I113
J 0
(-2750 4225);
DISPLAY 1.021277 (-2750 4225);
DISPLAY INVISIBLE (-2750 4225);
FORCEADD TAP..1
R 2
(-1875 4075);
FORCEPROP 3 LASTPIN (-1825 4075) SIG_NAME M_E_CPU0_SA_CA<5>
J 0
(-1815 4085);
DISPLAY 0.659574 (-1815 4085);
PAINT MONO (-1815 4085);
DISPLAY INVISIBLE (-1815 4085);
FORCEPROP 1 LASTPIN (-1825 4075) BN 5
J 2
(-1813 4083);
DISPLAY 0.680851 (-1813 4083);
PAINT GREEN (-1813 4083);
FORCEPROP 2 LAST CDS_LIB standard
J 0
(-1875 4075);
DISPLAY INVISIBLE (-1875 4075);
FORCEPROP 1 LAST BODY_TYPE PLUMBING
J 2
(-1875 4125);
DISPLAY 0.872340 (-1875 4125);
PAINT GREEN (-1875 4125);
DISPLAY INVISIBLE (-1875 4125);
FORCEPROP 1 LAST HDL_TAP TRUE
J 2
(-2200 3950);
DISPLAY 0.872340 (-2200 3950);
DISPLAY INVISIBLE (-2200 3950);
FORCEPROP 1 LAST PATH I114
J 2
(-1873 4075);
DISPLAY 0.872340 (-1873 4075);
PAINT GREEN (-1873 4075);
DISPLAY INVISIBLE (-1873 4075);
FORCEADD TAP..1
R 2
(-1875 4025);
FORCEPROP 3 LASTPIN (-1825 4025) SIG_NAME M_E_CPU0_SA_CA<4>
J 0
(-1815 4035);
DISPLAY 0.659574 (-1815 4035);
PAINT MONO (-1815 4035);
DISPLAY INVISIBLE (-1815 4035);
FORCEPROP 1 LASTPIN (-1825 4025) BN 4
J 2
(-1813 4033);
DISPLAY 0.680851 (-1813 4033);
PAINT GREEN (-1813 4033);
FORCEPROP 2 LAST CDS_LIB standard
J 0
(-1875 4025);
DISPLAY INVISIBLE (-1875 4025);
FORCEPROP 1 LAST BODY_TYPE PLUMBING
J 2
(-1875 4075);
DISPLAY 0.872340 (-1875 4075);
PAINT GREEN (-1875 4075);
DISPLAY INVISIBLE (-1875 4075);
FORCEPROP 1 LAST HDL_TAP TRUE
J 2
(-2200 3900);
DISPLAY 0.872340 (-2200 3900);
DISPLAY INVISIBLE (-2200 3900);
FORCEPROP 1 LAST PATH I115
J 2
(-1873 4025);
DISPLAY 0.872340 (-1873 4025);
PAINT GREEN (-1873 4025);
DISPLAY INVISIBLE (-1873 4025);
FORCEADD TAP..1
R 2
(-1875 4125);
FORCEPROP 3 LASTPIN (-1825 4125) SIG_NAME M_E_CPU0_SA_CA<6>
J 0
(-1815 4135);
DISPLAY 0.659574 (-1815 4135);
PAINT MONO (-1815 4135);
DISPLAY INVISIBLE (-1815 4135);
FORCEPROP 1 LASTPIN (-1825 4125) BN 6
J 2
(-1813 4133);
DISPLAY 0.680851 (-1813 4133);
PAINT GREEN (-1813 4133);
FORCEPROP 2 LAST CDS_LIB standard
J 0
(-1875 4125);
DISPLAY INVISIBLE (-1875 4125);
FORCEPROP 1 LAST BODY_TYPE PLUMBING
J 2
(-1875 4175);
DISPLAY 0.872340 (-1875 4175);
PAINT GREEN (-1875 4175);
DISPLAY INVISIBLE (-1875 4175);
FORCEPROP 1 LAST HDL_TAP TRUE
J 2
(-2200 4000);
DISPLAY 0.872340 (-2200 4000);
DISPLAY INVISIBLE (-2200 4000);
FORCEPROP 1 LAST PATH I116
J 2
(-1873 4125);
DISPLAY 0.872340 (-1873 4125);
PAINT GREEN (-1873 4125);
DISPLAY INVISIBLE (-1873 4125);
FORCEADD TAP..1
(-225 4125);
FORCEPROP 3 LASTPIN (-275 4125) SIG_NAME M_E_CPU0_SA_DQ<31>
J 0
(-265 4135);
DISPLAY 0.659574 (-265 4135);
PAINT MONO (-265 4135);
DISPLAY INVISIBLE (-265 4135);
FORCEPROP 1 LASTPIN (-275 4125) BN 31
J 0
(-287 4133);
DISPLAY 0.680851 (-287 4133);
PAINT GREEN (-287 4133);
FORCEPROP 2 LAST CDS_LIB standard
J 0
(-225 4125);
DISPLAY INVISIBLE (-225 4125);
FORCEPROP 1 LAST BODY_TYPE PLUMBING
J 0
(-225 4175);
DISPLAY 0.872340 (-225 4175);
PAINT GREEN (-225 4175);
DISPLAY INVISIBLE (-225 4175);
FORCEPROP 1 LAST HDL_TAP TRUE
J 0
(100 4000);
DISPLAY 0.872340 (100 4000);
DISPLAY INVISIBLE (100 4000);
FORCEPROP 1 LAST PATH I117
J 0
(-227 4125);
DISPLAY 0.872340 (-227 4125);
PAINT GREEN (-227 4125);
DISPLAY INVISIBLE (-227 4125);
FORCEADD TAP..1
(-225 4075);
FORCEPROP 3 LASTPIN (-275 4075) SIG_NAME M_E_CPU0_SA_DQ<30>
J 0
(-265 4085);
DISPLAY 0.659574 (-265 4085);
PAINT MONO (-265 4085);
DISPLAY INVISIBLE (-265 4085);
FORCEPROP 1 LASTPIN (-275 4075) BN 30
J 0
(-287 4083);
DISPLAY 0.680851 (-287 4083);
PAINT GREEN (-287 4083);
FORCEPROP 2 LAST CDS_LIB standard
J 0
(-225 4075);
DISPLAY INVISIBLE (-225 4075);
FORCEPROP 1 LAST BODY_TYPE PLUMBING
J 0
(-225 4125);
DISPLAY 0.872340 (-225 4125);
PAINT GREEN (-225 4125);
DISPLAY INVISIBLE (-225 4125);
FORCEPROP 1 LAST HDL_TAP TRUE
J 0
(100 3950);
DISPLAY 0.872340 (100 3950);
DISPLAY INVISIBLE (100 3950);
FORCEPROP 1 LAST PATH I118
J 0
(-227 4075);
DISPLAY 0.872340 (-227 4075);
PAINT GREEN (-227 4075);
DISPLAY INVISIBLE (-227 4075);
FORCEADD TAP..1
(-225 4025);
FORCEPROP 3 LASTPIN (-275 4025) SIG_NAME M_E_CPU0_SA_DQ<29>
J 0
(-265 4035);
DISPLAY 0.659574 (-265 4035);
PAINT MONO (-265 4035);
DISPLAY INVISIBLE (-265 4035);
FORCEPROP 1 LASTPIN (-275 4025) BN 29
J 0
(-287 4033);
DISPLAY 0.680851 (-287 4033);
PAINT GREEN (-287 4033);
FORCEPROP 2 LAST CDS_LIB standard
J 0
(-225 4025);
DISPLAY INVISIBLE (-225 4025);
FORCEPROP 1 LAST BODY_TYPE PLUMBING
J 0
(-225 4075);
DISPLAY 0.872340 (-225 4075);
PAINT GREEN (-225 4075);
DISPLAY INVISIBLE (-225 4075);
FORCEPROP 1 LAST HDL_TAP TRUE
J 0
(100 3900);
DISPLAY 0.872340 (100 3900);
DISPLAY INVISIBLE (100 3900);
FORCEPROP 1 LAST PATH I119
J 0
(-227 4025);
DISPLAY 0.872340 (-227 4025);
PAINT GREEN (-227 4025);
DISPLAY INVISIBLE (-227 4025);
FORCEADD VCC_CORE..1
(-2700 2000);
FORCEPROP 3 LASTPIN (-2700 1950) SIG_NAME P3V3_AUX\g
J 0
(-2690 1960);
DISPLAY 0.659574 (-2690 1960);
PAINT MONO (-2690 1960);
DISPLAY INVISIBLE (-2690 1960);
FORCEPROP 1 LAST HDL_POWER P3V3_AUX
J 1
(-2700 2050);
DISPLAY 1.148936 (-2700 2050);
PAINT GREEN (-2700 2050);
FORCEPROP 2 LAST CDS_LIB logical_power
J 0
(-2700 2000);
PAINT MONO (-2700 2000);
DISPLAY INVISIBLE (-2700 2000);
FORCEPROP 1 LAST PATH I12
J 0
(-2650 2025);
DISPLAY 0.872340 (-2650 2025);
PAINT AQUA (-2650 2025);
DISPLAY INVISIBLE (-2650 2025);
FORCEADD UNIVERSAL_GND..1
(1500 -125);
FORCEPROP 3 LASTPIN (1500 -75) SIG_NAME GND\g
J 0
(1510 -65);
DISPLAY 0.659574 (1510 -65);
PAINT MONO (1510 -65);
DISPLAY INVISIBLE (1510 -65);
FORCEPROP 2 LAST CDS_LIB logical_power
J 0
(1500 -125);
PAINT MONO (1500 -125);
DISPLAY INVISIBLE (1500 -125);
FORCEPROP 1 LAST HDL_POWER GND
J 1
(1525 -200);
DISPLAY 0.872340 (1525 -200);
PAINT GREEN (1525 -200);
DISPLAY INVISIBLE (1525 -200);
FORCEPROP 1 LAST PATH I120
J 0
(1575 -125);
DISPLAY 0.872340 (1575 -125);
PAINT AQUA (1575 -125);
DISPLAY INVISIBLE (1575 -125);
FORCEADD UNIVERSAL_GND..1
(3125 -125);
FORCEPROP 3 LASTPIN (3125 -75) SIG_NAME GND\g
J 0
(3135 -65);
DISPLAY 0.659574 (3135 -65);
PAINT MONO (3135 -65);
DISPLAY INVISIBLE (3135 -65);
FORCEPROP 2 LAST CDS_LIB logical_power
J 0
(3125 -125);
PAINT MONO (3125 -125);
DISPLAY INVISIBLE (3125 -125);
FORCEPROP 1 LAST HDL_POWER GND
J 1
(3150 -200);
DISPLAY 0.872340 (3150 -200);
PAINT GREEN (3150 -200);
DISPLAY INVISIBLE (3150 -200);
FORCEPROP 1 LAST PATH I121
J 0
(3200 -125);
DISPLAY 0.872340 (3200 -125);
PAINT AQUA (3200 -125);
DISPLAY INVISIBLE (3200 -125);
FORCEADD VCC_CORE..1
(1500 575);
FORCEPROP 3 LASTPIN (1500 525) SIG_NAME P3V3_AUX\g
J 0
(1510 535);
DISPLAY 0.659574 (1510 535);
PAINT MONO (1510 535);
DISPLAY INVISIBLE (1510 535);
FORCEPROP 1 LAST HDL_POWER P3V3_AUX
J 1
(1500 625);
DISPLAY 1.148936 (1500 625);
PAINT GREEN (1500 625);
FORCEPROP 2 LAST CDS_LIB logical_power
J 0
(1500 575);
PAINT MONO (1500 575);
DISPLAY INVISIBLE (1500 575);
FORCEPROP 1 LAST PATH I122
J 0
(1550 600);
DISPLAY 0.872340 (1550 600);
PAINT AQUA (1550 600);
DISPLAY INVISIBLE (1550 600);
FORCEADD Q_CAP..1
(1500 250);
FORCEPROP 1 LAST PART_NUMBER CH5221MEB00
J 0
(1550 100);
DISPLAY 0.978723 (1550 100);
DISPLAY INVISIBLE (1550 100);
FORCEPROP 1 LAST VALUE 2.2UF
J 0
(1550 300);
DISPLAY 0.978723 (1550 300);
FORCEPROP 1 LAST VOLTAGE 6.3V
J 0
(1550 250);
DISPLAY 0.978723 (1550 250);
FORCEPROP 1 LAST TOLERANCE 20%
J 0
(1550 200);
DISPLAY 0.978723 (1550 200);
FORCEPROP 1 LAST PACK_TYPE C0402
J 0
(1550 50);
DISPLAY 0.978723 (1550 50);
FORCEPROP 1 LAST MATERIAL X6S
J 0
(1550 150);
DISPLAY 0.978723 (1550 150);
FORCEPROP 1 LAST $LOCATION C29
J 0
(1550 350);
DISPLAY 0.978723 (1550 350);
FORCEPROP 1 LASTPIN (1500 350) $PN 1
J 0
(1510 330);
DISPLAY 0.787234 (1510 330);
FORCEPROP 1 LASTPIN (1500 150) $PN 2
J 0
(1510 130);
DISPLAY 0.787234 (1510 130);
FORCEPROP 2 LAST CDS_LIB pure_quanta
J 0
(1500 250);
PAINT MONO (1500 250);
DISPLAY INVISIBLE (1500 250);
FORCEPROP 2 LAST CDS_LOCATION C29
J 0
(1550 450);
DISPLAY 1.021277 (1550 450);
DISPLAY INVISIBLE (1550 450);
FORCEPROP 2 LAST $SEC 1
J 0
(1550 450);
DISPLAY 0.680851 (1550 450);
PAINT MONO (1550 450);
DISPLAY INVISIBLE (1550 450);
FORCEPROP 2 LAST CDS_SEC 1
J 0
(1550 450);
DISPLAY 1.021277 (1550 450);
DISPLAY INVISIBLE (1550 450);
FORCEPROP 1 LAST PATH I123
J 0
(1550 400);
DISPLAY 0.978723 (1550 400);
PAINT WHITE (1550 400);
DISPLAY INVISIBLE (1550 400);
FORCEADD Q_CAP..1
(2500 250);
FORCEPROP 1 LAST PART_NUMBER CH6103KEA00
J 0
(2550 100);
DISPLAY 0.978723 (2550 100);
DISPLAY INVISIBLE (2550 100);
FORCEPROP 1 LAST PACK_TYPE C0805
J 0
(2550 50);
DISPLAY 0.978723 (2550 50);
FORCEPROP 1 LAST TOLERANCE 10%
J 0
(2550 200);
DISPLAY 0.978723 (2550 200);
FORCEPROP 1 LAST VALUE 10UF
J 0
(2550 300);
DISPLAY 0.978723 (2550 300);
FORCEPROP 1 LAST VOLTAGE 16V
J 0
(2550 250);
DISPLAY 0.978723 (2550 250);
FORCEPROP 1 LAST MATERIAL X6S
J 0
(2550 150);
DISPLAY 0.978723 (2550 150);
FORCEPROP 1 LAST $LOCATION C30
J 0
(2550 350);
DISPLAY 0.978723 (2550 350);
FORCEPROP 1 LASTPIN (2500 350) $PN 1
J 0
(2510 330);
DISPLAY 0.787234 (2510 330);
FORCEPROP 1 LASTPIN (2500 150) $PN 2
J 0
(2510 130);
DISPLAY 0.787234 (2510 130);
FORCEPROP 2 LAST CDS_LIB pure_quanta
J 0
(2500 250);
PAINT MONO (2500 250);
DISPLAY INVISIBLE (2500 250);
FORCEPROP 2 LAST CDS_LOCATION C30
J 0
(2550 450);
DISPLAY 1.021277 (2550 450);
DISPLAY INVISIBLE (2550 450);
FORCEPROP 2 LAST $SEC 1
J 0
(2550 450);
DISPLAY 0.680851 (2550 450);
PAINT MONO (2550 450);
DISPLAY INVISIBLE (2550 450);
FORCEPROP 2 LAST CDS_SEC 1
J 0
(2550 450);
DISPLAY 1.021277 (2550 450);
DISPLAY INVISIBLE (2550 450);
FORCEPROP 1 LAST PATH I124
J 0
(2550 400);
DISPLAY 0.978723 (2550 400);
PAINT WHITE (2550 400);
DISPLAY INVISIBLE (2550 400);
FORCEADD VCC_CORE..1
(2500 575);
FORCEPROP 3 LASTPIN (2500 525) SIG_NAME P12V_S3_AUX_CPU0_NVDIMM\g
J 0
(2510 535);
DISPLAY 0.659574 (2510 535);
PAINT MONO (2510 535);
DISPLAY INVISIBLE (2510 535);
FORCEPROP 1 LAST HDL_POWER P12V_S3_AUX_CPU0_NVDIMM
J 1
(2500 625);
DISPLAY 1.148936 (2500 625);
PAINT GREEN (2500 625);
FORCEPROP 2 LAST CDS_LIB logical_power
J 0
(2500 575);
PAINT MONO (2500 575);
DISPLAY INVISIBLE (2500 575);
FORCEPROP 1 LAST PATH I125
J 0
(2550 600);
DISPLAY 0.872340 (2550 600);
PAINT AQUA (2550 600);
DISPLAY INVISIBLE (2550 600);
FORCEADD OFFPAGE..3
(600 2500);
FORCEPROP 2 LAST $XR1 90 
J 0
(904 2500);
DISPLAY 0.638298 (904 2500);
PAINT MONO (904 2500);
FORCEPROP 2 LAST $XR0 24 
J 0
(814 2500);
DISPLAY 0.638298 (814 2500);
PAINT MONO (814 2500);
FORCEPROP 2 LAST CDS_LIB standard
J 2
(600 2500);
DISPLAY INVISIBLE (600 2500);
FORCEPROP 1 LAST OFFPAGE TRUE
J 0
(925 2375);
DISPLAY 0.872340 (925 2375);
DISPLAY INVISIBLE (925 2375);
FORCEPROP 1 LAST COMMENT_BODY TRUE
J 0
(550 2400);
DISPLAY 0.872340 (550 2400);
PAINT GREEN (550 2400);
DISPLAY INVISIBLE (550 2400);
FORCEPROP 2 LAST PATH I126
J 0
(800 2575);
DISPLAY 1.021277 (800 2575);
DISPLAY INVISIBLE (800 2575);
FORCEADD TAP..1
(2525 2175);
FORCEPROP 3 LASTPIN (2475 2175) SIG_NAME M_E_CPU0_SB_DQS_DP<0>
J 0
(2485 2185);
DISPLAY 0.659574 (2485 2185);
PAINT MONO (2485 2185);
DISPLAY INVISIBLE (2485 2185);
FORCEPROP 1 LASTPIN (2475 2175) BN 0
J 0
(2463 2183);
DISPLAY 0.680851 (2463 2183);
PAINT GREEN (2463 2183);
FORCEPROP 2 LAST CDS_LIB standard
J 0
(2525 2175);
PAINT MONO (2525 2175);
DISPLAY INVISIBLE (2525 2175);
FORCEPROP 1 LAST BODY_TYPE PLUMBING
J 0
(2525 2225);
DISPLAY 0.872340 (2525 2225);
PAINT GREEN (2525 2225);
DISPLAY INVISIBLE (2525 2225);
FORCEPROP 1 LAST HDL_TAP TRUE
J 0
(2850 2050);
DISPLAY 0.872340 (2850 2050);
DISPLAY INVISIBLE (2850 2050);
FORCEPROP 1 LAST PATH I128
J 0
(2523 2175);
DISPLAY 0.872340 (2523 2175);
PAINT GREEN (2523 2175);
DISPLAY INVISIBLE (2523 2175);
FORCEADD TAP..1
(2525 2275);
FORCEPROP 3 LASTPIN (2475 2275) SIG_NAME M_E_CPU0_SB_DQS_DP<1>
J 0
(2485 2285);
DISPLAY 0.659574 (2485 2285);
PAINT MONO (2485 2285);
DISPLAY INVISIBLE (2485 2285);
FORCEPROP 1 LASTPIN (2475 2275) BN 1
J 0
(2463 2283);
DISPLAY 0.680851 (2463 2283);
PAINT GREEN (2463 2283);
FORCEPROP 2 LAST CDS_LIB standard
J 0
(2525 2275);
DISPLAY INVISIBLE (2525 2275);
FORCEPROP 1 LAST BODY_TYPE PLUMBING
J 0
(2525 2325);
DISPLAY 0.872340 (2525 2325);
PAINT GREEN (2525 2325);
DISPLAY INVISIBLE (2525 2325);
FORCEPROP 1 LAST HDL_TAP TRUE
J 0
(2850 2150);
DISPLAY 0.872340 (2850 2150);
DISPLAY INVISIBLE (2850 2150);
FORCEPROP 1 LAST PATH I129
J 0
(2523 2275);
DISPLAY 0.872340 (2523 2275);
PAINT GREEN (2523 2275);
DISPLAY INVISIBLE (2523 2275);
FORCEADD SCONN288_ADR50017P087CC..1
(-1050 2400);
FORCEPROP 1 LAST PART_NUMBER DFHST8FS460
J 0
(-1495 4410);
DISPLAY 0.723404 (-1495 4410);
PAINT GREEN (-1495 4410);
DISPLAY INVISIBLE (-1495 4410);
FORCEPROP 1 LAST MATERIAL IO
J 0
(-1495 4283);
DISPLAY 0.723404 (-1495 4283);
PAINT GREEN (-1495 4283);
FORCEPROP 2 LAST PART_TYPE SMLF
J 0
(-1500 4575);
DISPLAY 1.021277 (-1500 4575);
FORCEPROP 2 LAST VALUE SCONN288_ADR50017-P087CC
J 0
(-1500 4525);
DISPLAY 1.021277 (-1500 4525);
FORCEPROP 1 LAST $LOCATION J10
J 0
(-1500 4475);
DISPLAY 0.723404 (-1500 4475);
PAINT GREEN (-1500 4475);
FORCEPROP 0 LASTPIN (-1650 1775) $PN 62
J 2
(-1660 1785);
DISPLAY 0.680851 (-1660 1785);
PAINT MONO (-1660 1785);
FORCEPROP 0 LASTPIN (-1650 3825) $PN 66
J 2
(-1660 3835);
DISPLAY 0.680851 (-1660 3835);
PAINT MONO (-1660 3835);
FORCEPROP 0 LASTPIN (-1650 3425) $PN 76
J 2
(-1660 3435);
DISPLAY 0.680851 (-1660 3435);
PAINT MONO (-1660 3435);
FORCEPROP 0 LASTPIN (-1650 3875) $PN 211
J 2
(-1660 3885);
DISPLAY 0.680851 (-1660 3885);
PAINT MONO (-1660 3885);
FORCEPROP 0 LASTPIN (-1650 3475) $PN 221
J 2
(-1660 3485);
DISPLAY 0.680851 (-1660 3485);
PAINT MONO (-1660 3485);
FORCEPROP 0 LASTPIN (-1650 3925) $PN 68
J 2
(-1660 3935);
DISPLAY 0.680851 (-1660 3935);
PAINT MONO (-1660 3935);
FORCEPROP 0 LASTPIN (-1650 3525) $PN 78
J 2
(-1660 3535);
DISPLAY 0.680851 (-1660 3535);
PAINT MONO (-1660 3535);
FORCEPROP 0 LASTPIN (-1650 3975) $PN 213
J 2
(-1660 3985);
DISPLAY 0.680851 (-1660 3985);
PAINT MONO (-1660 3985);
FORCEPROP 0 LASTPIN (-1650 3575) $PN 223
J 2
(-1660 3585);
DISPLAY 0.680851 (-1660 3585);
PAINT MONO (-1660 3585);
FORCEPROP 0 LASTPIN (-1650 4025) $PN 70
J 2
(-1660 4035);
DISPLAY 0.680851 (-1660 4035);
PAINT MONO (-1660 4035);
FORCEPROP 0 LASTPIN (-1650 3625) $PN 80
J 2
(-1660 3635);
DISPLAY 0.680851 (-1660 3635);
PAINT MONO (-1660 3635);
FORCEPROP 0 LASTPIN (-1650 4075) $PN 215
J 2
(-1660 4085);
DISPLAY 0.680851 (-1660 4085);
PAINT MONO (-1660 4085);
FORCEPROP 0 LASTPIN (-1650 3675) $PN 225
J 2
(-1660 3685);
DISPLAY 0.680851 (-1660 3685);
PAINT MONO (-1660 3685);
FORCEPROP 0 LASTPIN (-1650 4125) $PN 72
J 2
(-1660 4135);
DISPLAY 0.680851 (-1660 4135);
PAINT MONO (-1660 4135);
FORCEPROP 0 LASTPIN (-1650 3725) $PN 82
J 2
(-1660 3735);
DISPLAY 0.680851 (-1660 3735);
PAINT MONO (-1660 3735);
FORCEPROP 0 LASTPIN (-1650 2375) $PN 51
J 2
(-1660 2385);
DISPLAY 0.680851 (-1660 2385);
PAINT MONO (-1660 2385);
FORCEPROP 0 LASTPIN (-1650 1925) $PN 96
J 2
(-1660 1935);
DISPLAY 0.680851 (-1660 1935);
PAINT MONO (-1660 1935);
FORCEPROP 0 LASTPIN (-1650 2425) $PN 53
J 2
(-1660 2435);
DISPLAY 0.680851 (-1660 2435);
PAINT MONO (-1660 2435);
FORCEPROP 0 LASTPIN (-1650 1975) $PN 98
J 2
(-1660 1985);
DISPLAY 0.680851 (-1660 1985);
PAINT MONO (-1660 1985);
FORCEPROP 0 LASTPIN (-1650 2475) $PN 196
J 2
(-1660 2485);
DISPLAY 0.680851 (-1660 2485);
PAINT MONO (-1660 2485);
FORCEPROP 0 LASTPIN (-1650 2025) $PN 241
J 2
(-1660 2035);
DISPLAY 0.680851 (-1660 2035);
PAINT MONO (-1660 2035);
FORCEPROP 0 LASTPIN (-1650 2525) $PN 198
J 2
(-1660 2535);
DISPLAY 0.680851 (-1660 2535);
PAINT MONO (-1660 2535);
FORCEPROP 0 LASTPIN (-1650 2075) $PN 243
J 2
(-1660 2085);
DISPLAY 0.680851 (-1660 2085);
PAINT MONO (-1660 2085);
FORCEPROP 0 LASTPIN (-1650 2575) $PN 58
J 2
(-1660 2585);
DISPLAY 0.680851 (-1660 2585);
PAINT MONO (-1660 2585);
FORCEPROP 0 LASTPIN (-1650 2125) $PN 89
J 2
(-1660 2135);
DISPLAY 0.680851 (-1660 2135);
PAINT MONO (-1660 2135);
FORCEPROP 0 LASTPIN (-1650 2625) $PN 60
J 2
(-1660 2635);
DISPLAY 0.680851 (-1660 2635);
PAINT MONO (-1660 2635);
FORCEPROP 0 LASTPIN (-1650 2175) $PN 91
J 2
(-1660 2185);
DISPLAY 0.680851 (-1660 2185);
PAINT MONO (-1660 2185);
FORCEPROP 0 LASTPIN (-1650 2675) $PN 203
J 2
(-1660 2685);
DISPLAY 0.680851 (-1660 2685);
PAINT MONO (-1660 2685);
FORCEPROP 0 LASTPIN (-1650 2225) $PN 234
J 2
(-1660 2235);
DISPLAY 0.680851 (-1660 2235);
PAINT MONO (-1660 2235);
FORCEPROP 0 LASTPIN (-1650 2725) $PN 205
J 2
(-1660 2735);
DISPLAY 0.680851 (-1660 2735);
PAINT MONO (-1660 2735);
FORCEPROP 0 LASTPIN (-1650 2275) $PN 236
J 2
(-1660 2285);
DISPLAY 0.680851 (-1660 2285);
PAINT MONO (-1660 2285);
FORCEPROP 0 LASTPIN (-1650 2825) $PN 218
J 2
(-1660 2835);
DISPLAY 0.680851 (-1660 2835);
PAINT MONO (-1660 2835);
FORCEPROP 0 LASTPIN (-1650 2875) $PN 217
J 2
(-1660 2885);
DISPLAY 0.680851 (-1660 2885);
PAINT MONO (-1660 2885);
FORCEPROP 0 LASTPIN (-1650 3125) $PN 64
J 2
(-1660 3135);
DISPLAY 0.680851 (-1660 3135);
PAINT MONO (-1660 3135);
FORCEPROP 0 LASTPIN (-1650 2975) $PN 84
J 2
(-1660 2985);
DISPLAY 0.680851 (-1660 2985);
PAINT MONO (-1660 2985);
FORCEPROP 0 LASTPIN (-1650 3175) $PN 209
J 2
(-1660 3185);
DISPLAY 0.680851 (-1660 3185);
PAINT MONO (-1660 3185);
FORCEPROP 0 LASTPIN (-1650 3025) $PN 229
J 2
(-1660 3035);
DISPLAY 0.680851 (-1660 3035);
PAINT MONO (-1660 3035);
FORCEPROP 0 LASTPIN (-450 2575) $PN 7
J 0
(-440 2585);
DISPLAY 0.680851 (-440 2585);
PAINT MONO (-440 2585);
FORCEPROP 0 LASTPIN (-450 925) $PN 100
J 0
(-440 935);
DISPLAY 0.680851 (-440 935);
PAINT MONO (-440 935);
FORCEPROP 0 LASTPIN (-450 2625) $PN 9
J 0
(-440 2635);
DISPLAY 0.680851 (-440 2635);
PAINT MONO (-440 2635);
FORCEPROP 0 LASTPIN (-450 975) $PN 102
J 0
(-440 985);
DISPLAY 0.680851 (-440 985);
PAINT MONO (-440 985);
FORCEPROP 0 LASTPIN (-450 2675) $PN 152
J 0
(-440 2685);
DISPLAY 0.680851 (-440 2685);
PAINT MONO (-440 2685);
FORCEPROP 0 LASTPIN (-450 1025) $PN 245
J 0
(-440 1035);
DISPLAY 0.680851 (-440 1035);
PAINT MONO (-440 1035);
FORCEPROP 0 LASTPIN (-450 2725) $PN 154
J 0
(-440 2735);
DISPLAY 0.680851 (-440 2735);
PAINT MONO (-440 2735);
FORCEPROP 0 LASTPIN (-450 1075) $PN 247
J 0
(-440 1085);
DISPLAY 0.680851 (-440 1085);
PAINT MONO (-440 1085);
FORCEPROP 0 LASTPIN (-450 2775) $PN 14
J 0
(-440 2785);
DISPLAY 0.680851 (-440 2785);
PAINT MONO (-440 2785);
FORCEPROP 0 LASTPIN (-450 1125) $PN 107
J 0
(-440 1135);
DISPLAY 0.680851 (-440 1135);
PAINT MONO (-440 1135);
FORCEPROP 0 LASTPIN (-450 2825) $PN 16
J 0
(-440 2835);
DISPLAY 0.680851 (-440 2835);
PAINT MONO (-440 2835);
FORCEPROP 0 LASTPIN (-450 1175) $PN 109
J 0
(-440 1185);
DISPLAY 0.680851 (-440 1185);
PAINT MONO (-440 1185);
FORCEPROP 0 LASTPIN (-450 2875) $PN 159
J 0
(-440 2885);
DISPLAY 0.680851 (-440 2885);
PAINT MONO (-440 2885);
FORCEPROP 0 LASTPIN (-450 1225) $PN 252
J 0
(-440 1235);
DISPLAY 0.680851 (-440 1235);
PAINT MONO (-440 1235);
FORCEPROP 0 LASTPIN (-450 2925) $PN 161
J 0
(-440 2935);
DISPLAY 0.680851 (-440 2935);
PAINT MONO (-440 2935);
FORCEPROP 0 LASTPIN (-450 1275) $PN 254
J 0
(-440 1285);
DISPLAY 0.680851 (-440 1285);
PAINT MONO (-440 1285);
FORCEPROP 0 LASTPIN (-450 2975) $PN 18
J 0
(-440 2985);
DISPLAY 0.680851 (-440 2985);
PAINT MONO (-440 2985);
FORCEPROP 0 LASTPIN (-450 1325) $PN 111
J 0
(-440 1335);
DISPLAY 0.680851 (-440 1335);
PAINT MONO (-440 1335);
FORCEPROP 0 LASTPIN (-450 3025) $PN 20
J 0
(-440 3035);
DISPLAY 0.680851 (-440 3035);
PAINT MONO (-440 3035);
FORCEPROP 0 LASTPIN (-450 1375) $PN 113
J 0
(-440 1385);
DISPLAY 0.680851 (-440 1385);
PAINT MONO (-440 1385);
FORCEPROP 0 LASTPIN (-450 3075) $PN 163
J 0
(-440 3085);
DISPLAY 0.680851 (-440 3085);
PAINT MONO (-440 3085);
FORCEPROP 0 LASTPIN (-450 1425) $PN 256
J 0
(-440 1435);
DISPLAY 0.680851 (-440 1435);
PAINT MONO (-440 1435);
FORCEPROP 0 LASTPIN (-450 3125) $PN 165
J 0
(-440 3135);
DISPLAY 0.680851 (-440 3135);
PAINT MONO (-440 3135);
FORCEPROP 0 LASTPIN (-450 1475) $PN 258
J 0
(-440 1485);
DISPLAY 0.680851 (-440 1485);
PAINT MONO (-440 1485);
FORCEPROP 0 LASTPIN (-450 3175) $PN 25
J 0
(-440 3185);
DISPLAY 0.680851 (-440 3185);
PAINT MONO (-440 3185);
FORCEPROP 0 LASTPIN (-450 1525) $PN 118
J 0
(-440 1535);
DISPLAY 0.680851 (-440 1535);
PAINT MONO (-440 1535);
FORCEPROP 0 LASTPIN (-450 3225) $PN 27
J 0
(-440 3235);
DISPLAY 0.680851 (-440 3235);
PAINT MONO (-440 3235);
FORCEPROP 0 LASTPIN (-450 1575) $PN 120
J 0
(-440 1585);
DISPLAY 0.680851 (-440 1585);
PAINT MONO (-440 1585);
FORCEPROP 0 LASTPIN (-450 3275) $PN 170
J 0
(-440 3285);
DISPLAY 0.680851 (-440 3285);
PAINT MONO (-440 3285);
FORCEPROP 0 LASTPIN (-450 1625) $PN 263
J 0
(-440 1635);
DISPLAY 0.680851 (-440 1635);
PAINT MONO (-440 1635);
FORCEPROP 0 LASTPIN (-450 3325) $PN 172
J 0
(-440 3335);
DISPLAY 0.680851 (-440 3335);
PAINT MONO (-440 3335);
FORCEPROP 0 LASTPIN (-450 1675) $PN 265
J 0
(-440 1685);
DISPLAY 0.680851 (-440 1685);
PAINT MONO (-440 1685);
FORCEPROP 0 LASTPIN (-450 3375) $PN 29
J 0
(-440 3385);
DISPLAY 0.680851 (-440 3385);
PAINT MONO (-440 3385);
FORCEPROP 0 LASTPIN (-450 1725) $PN 122
J 0
(-440 1735);
DISPLAY 0.680851 (-440 1735);
PAINT MONO (-440 1735);
FORCEPROP 0 LASTPIN (-450 3425) $PN 31
J 0
(-440 3435);
DISPLAY 0.680851 (-440 3435);
PAINT MONO (-440 3435);
FORCEPROP 0 LASTPIN (-450 1775) $PN 124
J 0
(-440 1785);
DISPLAY 0.680851 (-440 1785);
PAINT MONO (-440 1785);
FORCEPROP 0 LASTPIN (-450 3475) $PN 174
J 0
(-440 3485);
DISPLAY 0.680851 (-440 3485);
PAINT MONO (-440 3485);
FORCEPROP 0 LASTPIN (-450 1825) $PN 267
J 0
(-440 1835);
DISPLAY 0.680851 (-440 1835);
PAINT MONO (-440 1835);
FORCEPROP 0 LASTPIN (-450 3525) $PN 176
J 0
(-440 3535);
DISPLAY 0.680851 (-440 3535);
PAINT MONO (-440 3535);
FORCEPROP 0 LASTPIN (-450 1875) $PN 269
J 0
(-440 1885);
DISPLAY 0.680851 (-440 1885);
PAINT MONO (-440 1885);
FORCEPROP 0 LASTPIN (-450 3575) $PN 36
J 0
(-440 3585);
DISPLAY 0.680851 (-440 3585);
PAINT MONO (-440 3585);
FORCEPROP 0 LASTPIN (-450 1925) $PN 129
J 0
(-440 1935);
DISPLAY 0.680851 (-440 1935);
PAINT MONO (-440 1935);
FORCEPROP 0 LASTPIN (-450 3625) $PN 38
J 0
(-440 3635);
DISPLAY 0.680851 (-440 3635);
PAINT MONO (-440 3635);
FORCEPROP 0 LASTPIN (-450 1975) $PN 131
J 0
(-440 1985);
DISPLAY 0.680851 (-440 1985);
PAINT MONO (-440 1985);
FORCEPROP 0 LASTPIN (-450 3675) $PN 181
J 0
(-440 3685);
DISPLAY 0.680851 (-440 3685);
PAINT MONO (-440 3685);
FORCEPROP 0 LASTPIN (-450 2025) $PN 274
J 0
(-440 2035);
DISPLAY 0.680851 (-440 2035);
PAINT MONO (-440 2035);
FORCEPROP 0 LASTPIN (-450 3725) $PN 183
J 0
(-440 3735);
DISPLAY 0.680851 (-440 3735);
PAINT MONO (-440 3735);
FORCEPROP 0 LASTPIN (-450 2075) $PN 276
J 0
(-440 2085);
DISPLAY 0.680851 (-440 2085);
PAINT MONO (-440 2085);
FORCEPROP 0 LASTPIN (-450 3775) $PN 40
J 0
(-440 3785);
DISPLAY 0.680851 (-440 3785);
PAINT MONO (-440 3785);
FORCEPROP 0 LASTPIN (-450 2125) $PN 133
J 0
(-440 2135);
DISPLAY 0.680851 (-440 2135);
PAINT MONO (-440 2135);
FORCEPROP 0 LASTPIN (-450 3825) $PN 42
J 0
(-440 3835);
DISPLAY 0.680851 (-440 3835);
PAINT MONO (-440 3835);
FORCEPROP 0 LASTPIN (-450 2175) $PN 135
J 0
(-440 2185);
DISPLAY 0.680851 (-440 2185);
PAINT MONO (-440 2185);
FORCEPROP 0 LASTPIN (-450 3875) $PN 185
J 0
(-440 3885);
DISPLAY 0.680851 (-440 3885);
PAINT MONO (-440 3885);
FORCEPROP 0 LASTPIN (-450 2225) $PN 278
J 0
(-440 2235);
DISPLAY 0.680851 (-440 2235);
PAINT MONO (-440 2235);
FORCEPROP 0 LASTPIN (-450 3925) $PN 187
J 0
(-440 3935);
DISPLAY 0.680851 (-440 3935);
PAINT MONO (-440 3935);
FORCEPROP 0 LASTPIN (-450 2275) $PN 280
J 0
(-440 2285);
DISPLAY 0.680851 (-440 2285);
PAINT MONO (-440 2285);
FORCEPROP 0 LASTPIN (-450 3975) $PN 47
J 0
(-440 3985);
DISPLAY 0.680851 (-440 3985);
PAINT MONO (-440 3985);
FORCEPROP 0 LASTPIN (-450 2325) $PN 140
J 0
(-440 2335);
DISPLAY 0.680851 (-440 2335);
PAINT MONO (-440 2335);
FORCEPROP 0 LASTPIN (-450 4025) $PN 49
J 0
(-440 4035);
DISPLAY 0.680851 (-440 4035);
PAINT MONO (-440 4035);
FORCEPROP 0 LASTPIN (-450 2375) $PN 142
J 0
(-440 2385);
DISPLAY 0.680851 (-440 2385);
PAINT MONO (-440 2385);
FORCEPROP 0 LASTPIN (-450 4075) $PN 192
J 0
(-440 4085);
DISPLAY 0.680851 (-440 4085);
PAINT MONO (-440 4085);
FORCEPROP 0 LASTPIN (-450 2425) $PN 285
J 0
(-440 2435);
DISPLAY 0.680851 (-440 2435);
PAINT MONO (-440 2435);
FORCEPROP 0 LASTPIN (-450 4125) $PN 194
J 0
(-440 4135);
DISPLAY 0.680851 (-440 4135);
PAINT MONO (-440 4135);
FORCEPROP 0 LASTPIN (-450 2475) $PN 287
J 0
(-440 2485);
DISPLAY 0.680851 (-440 2485);
PAINT MONO (-440 2485);
FORCEPROP 0 LASTPIN (-1650 1625) $PN 148
J 2
(-1660 1635);
DISPLAY 0.680851 (-1660 1635);
PAINT MONO (-1660 1635);
FORCEPROP 0 LASTPIN (-1650 1525) $PN 4
J 2
(-1660 1535);
DISPLAY 0.680851 (-1660 1535);
PAINT MONO (-1660 1535);
FORCEPROP 0 LASTPIN (-1650 1575) $PN 5
J 2
(-1660 1585);
DISPLAY 0.680851 (-1660 1585);
PAINT MONO (-1660 1585);
FORCEPROP 0 LASTPIN (-1650 725) $PN 86
J 2
(-1660 735);
DISPLAY 0.680851 (-1660 735);
PAINT MONO (-1660 735);
FORCEPROP 0 LASTPIN (-1650 675) $PN 87
J 2
(-1660 685);
DISPLAY 0.680851 (-1660 685);
PAINT MONO (-1660 685);
FORCEPROP 0 LASTPIN (-1650 3325) $PN 74
J 2
(-1660 3335);
DISPLAY 0.680851 (-1660 3335);
PAINT MONO (-1660 3335);
FORCEPROP 0 LASTPIN (-1650 3275) $PN 227
J 2
(-1660 3285);
DISPLAY 0.680851 (-1660 3285);
PAINT MONO (-1660 3285);
FORCEPROP 0 LASTPIN (-1650 1275) $PN 147
J 2
(-1660 1285);
DISPLAY 0.680851 (-1660 1285);
PAINT MONO (-1660 1285);
FORCEPROP 0 LASTPIN (-1650 1825) $PN 207
J 2
(-1660 1835);
DISPLAY 0.680851 (-1660 1835);
PAINT MONO (-1660 1835);
FORCEPROP 0 LASTPIN (-1650 875) $PN 2
J 2
(-1660 885);
DISPLAY 0.680851 (-1660 885);
PAINT MONO (-1660 885);
FORCEPROP 0 LASTPIN (-1650 925) $PN 144
J 2
(-1660 935);
DISPLAY 0.680851 (-1660 935);
PAINT MONO (-1660 935);
FORCEPROP 0 LASTPIN (-1650 975) $PN 149
J 2
(-1660 985);
DISPLAY 0.680851 (-1660 985);
PAINT MONO (-1660 985);
FORCEPROP 0 LASTPIN (-1650 1025) $PN 150
J 2
(-1660 1035);
DISPLAY 0.680851 (-1660 1035);
PAINT MONO (-1660 1035);
FORCEPROP 0 LASTPIN (-1650 1075) $PN 220
J 2
(-1660 1085);
DISPLAY 0.680851 (-1660 1085);
PAINT MONO (-1660 1085);
FORCEPROP 0 LASTPIN (-1650 1125) $PN 231
J 2
(-1660 1135);
DISPLAY 0.680851 (-1660 1135);
PAINT MONO (-1660 1135);
FORCEPROP 0 LASTPIN (-1650 1175) $PN 232
J 2
(-1660 1185);
DISPLAY 0.680851 (-1660 1185);
PAINT MONO (-1660 1185);
FORCEPROP 0 LASTPIN (-1650 1675) $PN 3
J 2
(-1660 1685);
DISPLAY 0.680851 (-1660 1685);
PAINT MONO (-1660 1685);
FORCEPROP 1 LAST NEEDS_NO_SIZE TRUE
J 0
(-1050 2400);
DISPLAY 0.723404 (-1050 2400);
PAINT GREEN (-1050 2400);
DISPLAY INVISIBLE (-1050 2400);
FORCEPROP 1 LAST CDS_LMAN_SYM_OUTLINE -450,1875,450,-1875
J 0
(-1050 2400);
DISPLAY 0.468085 (-1050 2400);
PAINT GREEN (-1050 2400);
DISPLAY INVISIBLE (-1050 2400);
FORCEPROP 2 LAST CDS_LIB pure_quanta
J 0
(-1050 2400);
DISPLAY INVISIBLE (-1050 2400);
FORCEPROP 2 LAST CDS_LOCATION J10
J 0
(-1500 4625);
DISPLAY 1.021277 (-1500 4625);
DISPLAY INVISIBLE (-1500 4625);
FORCEPROP 0 LAST $SEC 1
J 0
(-1500 4625);
DISPLAY 0.680851 (-1500 4625);
PAINT MONO (-1500 4625);
DISPLAY INVISIBLE (-1500 4625);
FORCEPROP 2 LAST CDS_SEC 1
J 0
(-1500 4625);
DISPLAY 1.021277 (-1500 4625);
DISPLAY INVISIBLE (-1500 4625);
FORCEPROP 1 LAST PATH I13
J 0
(-1050 2400);
DISPLAY 0.723404 (-1050 2400);
PAINT GREEN (-1050 2400);
DISPLAY INVISIBLE (-1050 2400);
FORCEADD TAP..1
(2525 2475);
FORCEPROP 3 LASTPIN (2475 2475) SIG_NAME M_E_CPU0_SB_DQS_DP<3>
J 0
(2485 2485);
DISPLAY 0.659574 (2485 2485);
PAINT MONO (2485 2485);
DISPLAY INVISIBLE (2485 2485);
FORCEPROP 1 LASTPIN (2475 2475) BN 3
J 0
(2463 2483);
DISPLAY 0.680851 (2463 2483);
PAINT GREEN (2463 2483);
FORCEPROP 2 LAST CDS_LIB standard
J 0
(2525 2475);
PAINT MONO (2525 2475);
DISPLAY INVISIBLE (2525 2475);
FORCEPROP 1 LAST BODY_TYPE PLUMBING
J 0
(2525 2525);
DISPLAY 0.872340 (2525 2525);
PAINT GREEN (2525 2525);
DISPLAY INVISIBLE (2525 2525);
FORCEPROP 1 LAST HDL_TAP TRUE
J 0
(2850 2350);
DISPLAY 0.872340 (2850 2350);
DISPLAY INVISIBLE (2850 2350);
FORCEPROP 1 LAST PATH I130
J 0
(2523 2475);
DISPLAY 0.872340 (2523 2475);
PAINT GREEN (2523 2475);
DISPLAY INVISIBLE (2523 2475);
FORCEADD TAP..1
(2525 2375);
FORCEPROP 3 LASTPIN (2475 2375) SIG_NAME M_E_CPU0_SB_DQS_DP<2>
J 0
(2485 2385);
DISPLAY 0.659574 (2485 2385);
PAINT MONO (2485 2385);
DISPLAY INVISIBLE (2485 2385);
FORCEPROP 1 LASTPIN (2475 2375) BN 2
J 0
(2463 2383);
DISPLAY 0.680851 (2463 2383);
PAINT GREEN (2463 2383);
FORCEPROP 2 LAST CDS_LIB standard
J 0
(2525 2375);
DISPLAY INVISIBLE (2525 2375);
FORCEPROP 1 LAST BODY_TYPE PLUMBING
J 0
(2525 2425);
DISPLAY 0.872340 (2525 2425);
PAINT GREEN (2525 2425);
DISPLAY INVISIBLE (2525 2425);
FORCEPROP 1 LAST HDL_TAP TRUE
J 0
(2850 2250);
DISPLAY 0.872340 (2850 2250);
DISPLAY INVISIBLE (2850 2250);
FORCEPROP 1 LAST PATH I131
J 0
(2523 2375);
DISPLAY 0.872340 (2523 2375);
PAINT GREEN (2523 2375);
DISPLAY INVISIBLE (2523 2375);
FORCEADD TAP..1
(2525 2575);
FORCEPROP 3 LASTPIN (2475 2575) SIG_NAME M_E_CPU0_SB_DQS_DP<4>
J 0
(2485 2585);
DISPLAY 0.659574 (2485 2585);
PAINT MONO (2485 2585);
DISPLAY INVISIBLE (2485 2585);
FORCEPROP 1 LASTPIN (2475 2575) BN 4
J 0
(2463 2583);
DISPLAY 0.680851 (2463 2583);
PAINT GREEN (2463 2583);
FORCEPROP 2 LAST CDS_LIB standard
J 0
(2525 2575);
PAINT MONO (2525 2575);
DISPLAY INVISIBLE (2525 2575);
FORCEPROP 1 LAST BODY_TYPE PLUMBING
J 0
(2525 2625);
DISPLAY 0.872340 (2525 2625);
PAINT GREEN (2525 2625);
DISPLAY INVISIBLE (2525 2625);
FORCEPROP 1 LAST HDL_TAP TRUE
J 0
(2850 2450);
DISPLAY 0.872340 (2850 2450);
DISPLAY INVISIBLE (2850 2450);
FORCEPROP 1 LAST PATH I132
J 0
(2523 2575);
DISPLAY 0.872340 (2523 2575);
PAINT GREEN (2523 2575);
DISPLAY INVISIBLE (2523 2575);
FORCEADD TAP..1
(2525 2675);
FORCEPROP 3 LASTPIN (2475 2675) SIG_NAME M_E_CPU0_SB_DQS_DP<5>
J 0
(2485 2685);
DISPLAY 0.659574 (2485 2685);
PAINT MONO (2485 2685);
DISPLAY INVISIBLE (2485 2685);
FORCEPROP 1 LASTPIN (2475 2675) BN 5
J 0
(2463 2683);
DISPLAY 0.680851 (2463 2683);
PAINT GREEN (2463 2683);
FORCEPROP 2 LAST CDS_LIB standard
J 0
(2525 2675);
DISPLAY INVISIBLE (2525 2675);
FORCEPROP 1 LAST BODY_TYPE PLUMBING
J 0
(2525 2725);
DISPLAY 0.872340 (2525 2725);
PAINT GREEN (2525 2725);
DISPLAY INVISIBLE (2525 2725);
FORCEPROP 1 LAST HDL_TAP TRUE
J 0
(2850 2550);
DISPLAY 0.872340 (2850 2550);
DISPLAY INVISIBLE (2850 2550);
FORCEPROP 1 LAST PATH I133
J 0
(2523 2675);
DISPLAY 0.872340 (2523 2675);
PAINT GREEN (2523 2675);
DISPLAY INVISIBLE (2523 2675);
FORCEADD TAP..1
(2525 2775);
FORCEPROP 3 LASTPIN (2475 2775) SIG_NAME M_E_CPU0_SB_DQS_DP<6>
J 0
(2485 2785);
DISPLAY 0.659574 (2485 2785);
PAINT MONO (2485 2785);
DISPLAY INVISIBLE (2485 2785);
FORCEPROP 1 LASTPIN (2475 2775) BN 6
J 0
(2463 2783);
DISPLAY 0.680851 (2463 2783);
PAINT GREEN (2463 2783);
FORCEPROP 2 LAST CDS_LIB standard
J 0
(2525 2775);
DISPLAY INVISIBLE (2525 2775);
FORCEPROP 1 LAST BODY_TYPE PLUMBING
J 0
(2525 2825);
DISPLAY 0.872340 (2525 2825);
PAINT GREEN (2525 2825);
DISPLAY INVISIBLE (2525 2825);
FORCEPROP 1 LAST HDL_TAP TRUE
J 0
(2850 2650);
DISPLAY 0.872340 (2850 2650);
DISPLAY INVISIBLE (2850 2650);
FORCEPROP 1 LAST PATH I134
J 0
(2523 2775);
DISPLAY 0.872340 (2523 2775);
PAINT GREEN (2523 2775);
DISPLAY INVISIBLE (2523 2775);
FORCEADD TAP..1
(2525 2975);
FORCEPROP 3 LASTPIN (2475 2975) SIG_NAME M_E_CPU0_SB_DQS_DP<8>
J 0
(2485 2985);
DISPLAY 0.659574 (2485 2985);
PAINT MONO (2485 2985);
DISPLAY INVISIBLE (2485 2985);
FORCEPROP 1 LASTPIN (2475 2975) BN 8
J 0
(2463 2983);
DISPLAY 0.680851 (2463 2983);
PAINT GREEN (2463 2983);
FORCEPROP 2 LAST CDS_LIB standard
J 0
(2525 2975);
DISPLAY INVISIBLE (2525 2975);
FORCEPROP 1 LAST BODY_TYPE PLUMBING
J 0
(2525 3025);
DISPLAY 0.872340 (2525 3025);
PAINT GREEN (2525 3025);
DISPLAY INVISIBLE (2525 3025);
FORCEPROP 1 LAST HDL_TAP TRUE
J 0
(2850 2850);
DISPLAY 0.872340 (2850 2850);
DISPLAY INVISIBLE (2850 2850);
FORCEPROP 1 LAST PATH I135
J 0
(2523 2975);
DISPLAY 0.872340 (2523 2975);
PAINT GREEN (2523 2975);
DISPLAY INVISIBLE (2523 2975);
FORCEADD TAP..1
(2525 2875);
FORCEPROP 3 LASTPIN (2475 2875) SIG_NAME M_E_CPU0_SB_DQS_DP<7>
J 0
(2485 2885);
DISPLAY 0.659574 (2485 2885);
PAINT MONO (2485 2885);
DISPLAY INVISIBLE (2485 2885);
FORCEPROP 1 LASTPIN (2475 2875) BN 7
J 0
(2463 2883);
DISPLAY 0.680851 (2463 2883);
PAINT GREEN (2463 2883);
FORCEPROP 2 LAST CDS_LIB standard
J 0
(2525 2875);
DISPLAY INVISIBLE (2525 2875);
FORCEPROP 1 LAST BODY_TYPE PLUMBING
J 0
(2525 2925);
DISPLAY 0.872340 (2525 2925);
PAINT GREEN (2525 2925);
DISPLAY INVISIBLE (2525 2925);
FORCEPROP 1 LAST HDL_TAP TRUE
J 0
(2850 2750);
DISPLAY 0.872340 (2850 2750);
DISPLAY INVISIBLE (2850 2750);
FORCEPROP 1 LAST PATH I136
J 0
(2523 2875);
DISPLAY 0.872340 (2523 2875);
PAINT GREEN (2523 2875);
DISPLAY INVISIBLE (2523 2875);
FORCEADD TAP..1
(2525 3225);
FORCEPROP 3 LASTPIN (2475 3225) SIG_NAME M_E_CPU0_SA_DQS_DP<0>
J 0
(2485 3235);
DISPLAY 0.659574 (2485 3235);
PAINT MONO (2485 3235);
DISPLAY INVISIBLE (2485 3235);
FORCEPROP 1 LASTPIN (2475 3225) BN 0
J 0
(2463 3233);
DISPLAY 0.680851 (2463 3233);
PAINT GREEN (2463 3233);
FORCEPROP 2 LAST CDS_LIB standard
J 0
(2525 3225);
PAINT MONO (2525 3225);
DISPLAY INVISIBLE (2525 3225);
FORCEPROP 1 LAST BODY_TYPE PLUMBING
J 0
(2525 3275);
DISPLAY 0.872340 (2525 3275);
PAINT GREEN (2525 3275);
DISPLAY INVISIBLE (2525 3275);
FORCEPROP 1 LAST HDL_TAP TRUE
J 0
(2850 3100);
DISPLAY 0.872340 (2850 3100);
DISPLAY INVISIBLE (2850 3100);
FORCEPROP 1 LAST PATH I137
J 0
(2523 3225);
DISPLAY 0.872340 (2523 3225);
PAINT GREEN (2523 3225);
DISPLAY INVISIBLE (2523 3225);
FORCEADD TAP..1
(2525 3075);
FORCEPROP 3 LASTPIN (2475 3075) SIG_NAME M_E_CPU0_SB_DQS_DP<9>
J 0
(2485 3085);
DISPLAY 0.659574 (2485 3085);
PAINT MONO (2485 3085);
DISPLAY INVISIBLE (2485 3085);
FORCEPROP 1 LASTPIN (2475 3075) BN 9
J 0
(2463 3083);
DISPLAY 0.680851 (2463 3083);
PAINT GREEN (2463 3083);
FORCEPROP 2 LAST CDS_LIB standard
J 0
(2525 3075);
DISPLAY INVISIBLE (2525 3075);
FORCEPROP 1 LAST BODY_TYPE PLUMBING
J 0
(2525 3125);
DISPLAY 0.872340 (2525 3125);
PAINT GREEN (2525 3125);
DISPLAY INVISIBLE (2525 3125);
FORCEPROP 1 LAST HDL_TAP TRUE
J 0
(2850 2950);
DISPLAY 0.872340 (2850 2950);
DISPLAY INVISIBLE (2850 2950);
FORCEPROP 1 LAST PATH I138
J 0
(2523 3075);
DISPLAY 0.872340 (2523 3075);
PAINT GREEN (2523 3075);
DISPLAY INVISIBLE (2523 3075);
FORCEADD TAP..1
(2525 3325);
FORCEPROP 3 LASTPIN (2475 3325) SIG_NAME M_E_CPU0_SA_DQS_DP<1>
J 0
(2485 3335);
DISPLAY 0.659574 (2485 3335);
PAINT MONO (2485 3335);
DISPLAY INVISIBLE (2485 3335);
FORCEPROP 1 LASTPIN (2475 3325) BN 1
J 0
(2463 3333);
DISPLAY 0.680851 (2463 3333);
PAINT GREEN (2463 3333);
FORCEPROP 2 LAST CDS_LIB standard
J 0
(2525 3325);
DISPLAY INVISIBLE (2525 3325);
FORCEPROP 1 LAST BODY_TYPE PLUMBING
J 0
(2525 3375);
DISPLAY 0.872340 (2525 3375);
PAINT GREEN (2525 3375);
DISPLAY INVISIBLE (2525 3375);
FORCEPROP 1 LAST HDL_TAP TRUE
J 0
(2850 3200);
DISPLAY 0.872340 (2850 3200);
DISPLAY INVISIBLE (2850 3200);
FORCEPROP 1 LAST PATH I139
J 0
(2523 3325);
DISPLAY 0.872340 (2523 3325);
PAINT GREEN (2523 3325);
DISPLAY INVISIBLE (2523 3325);
FORCEADD TAP..1
R 2
(-1875 1925);
FORCEPROP 3 LASTPIN (-1825 1925) SIG_NAME M_E_CPU0_SB_CB<0>
J 0
(-1815 1935);
DISPLAY 0.659574 (-1815 1935);
PAINT MONO (-1815 1935);
DISPLAY INVISIBLE (-1815 1935);
FORCEPROP 1 LASTPIN (-1825 1925) BN 0
J 2
(-1813 1933);
DISPLAY 0.680851 (-1813 1933);
PAINT GREEN (-1813 1933);
FORCEPROP 2 LAST CDS_LIB standard
J 0
(-1875 1925);
PAINT MONO (-1875 1925);
DISPLAY INVISIBLE (-1875 1925);
FORCEPROP 1 LAST BODY_TYPE PLUMBING
J 2
(-1875 1975);
DISPLAY 0.872340 (-1875 1975);
PAINT GREEN (-1875 1975);
DISPLAY INVISIBLE (-1875 1975);
FORCEPROP 1 LAST HDL_TAP TRUE
J 2
(-2200 1800);
DISPLAY 0.872340 (-2200 1800);
DISPLAY INVISIBLE (-2200 1800);
FORCEPROP 1 LAST PATH I14
J 2
(-1873 1925);
DISPLAY 0.872340 (-1873 1925);
PAINT GREEN (-1873 1925);
DISPLAY INVISIBLE (-1873 1925);
FORCEADD TAP..1
(2525 3425);
FORCEPROP 3 LASTPIN (2475 3425) SIG_NAME M_E_CPU0_SA_DQS_DP<2>
J 0
(2485 3435);
DISPLAY 0.659574 (2485 3435);
PAINT MONO (2485 3435);
DISPLAY INVISIBLE (2485 3435);
FORCEPROP 1 LASTPIN (2475 3425) BN 2
J 0
(2463 3433);
DISPLAY 0.680851 (2463 3433);
PAINT GREEN (2463 3433);
FORCEPROP 2 LAST CDS_LIB standard
J 0
(2525 3425);
DISPLAY INVISIBLE (2525 3425);
FORCEPROP 1 LAST BODY_TYPE PLUMBING
J 0
(2525 3475);
DISPLAY 0.872340 (2525 3475);
PAINT GREEN (2525 3475);
DISPLAY INVISIBLE (2525 3475);
FORCEPROP 1 LAST HDL_TAP TRUE
J 0
(2850 3300);
DISPLAY 0.872340 (2850 3300);
DISPLAY INVISIBLE (2850 3300);
FORCEPROP 1 LAST PATH I140
J 0
(2523 3425);
DISPLAY 0.872340 (2523 3425);
PAINT GREEN (2523 3425);
DISPLAY INVISIBLE (2523 3425);
FORCEADD TAP..1
(2525 3525);
FORCEPROP 3 LASTPIN (2475 3525) SIG_NAME M_E_CPU0_SA_DQS_DP<3>
J 0
(2485 3535);
DISPLAY 0.659574 (2485 3535);
PAINT MONO (2485 3535);
DISPLAY INVISIBLE (2485 3535);
FORCEPROP 1 LASTPIN (2475 3525) BN 3
J 0
(2463 3533);
DISPLAY 0.680851 (2463 3533);
PAINT GREEN (2463 3533);
FORCEPROP 2 LAST CDS_LIB standard
J 0
(2525 3525);
PAINT MONO (2525 3525);
DISPLAY INVISIBLE (2525 3525);
FORCEPROP 1 LAST BODY_TYPE PLUMBING
J 0
(2525 3575);
DISPLAY 0.872340 (2525 3575);
PAINT GREEN (2525 3575);
DISPLAY INVISIBLE (2525 3575);
FORCEPROP 1 LAST HDL_TAP TRUE
J 0
(2850 3400);
DISPLAY 0.872340 (2850 3400);
DISPLAY INVISIBLE (2850 3400);
FORCEPROP 1 LAST PATH I141
J 0
(2523 3525);
DISPLAY 0.872340 (2523 3525);
PAINT GREEN (2523 3525);
DISPLAY INVISIBLE (2523 3525);
FORCEADD TAP..1
(2525 3625);
FORCEPROP 3 LASTPIN (2475 3625) SIG_NAME M_E_CPU0_SA_DQS_DP<4>
J 0
(2485 3635);
DISPLAY 0.659574 (2485 3635);
PAINT MONO (2485 3635);
DISPLAY INVISIBLE (2485 3635);
FORCEPROP 1 LASTPIN (2475 3625) BN 4
J 0
(2463 3633);
DISPLAY 0.680851 (2463 3633);
PAINT GREEN (2463 3633);
FORCEPROP 2 LAST CDS_LIB standard
J 0
(2525 3625);
PAINT MONO (2525 3625);
DISPLAY INVISIBLE (2525 3625);
FORCEPROP 1 LAST BODY_TYPE PLUMBING
J 0
(2525 3675);
DISPLAY 0.872340 (2525 3675);
PAINT GREEN (2525 3675);
DISPLAY INVISIBLE (2525 3675);
FORCEPROP 1 LAST HDL_TAP TRUE
J 0
(2850 3500);
DISPLAY 0.872340 (2850 3500);
DISPLAY INVISIBLE (2850 3500);
FORCEPROP 1 LAST PATH I142
J 0
(2523 3625);
DISPLAY 0.872340 (2523 3625);
PAINT GREEN (2523 3625);
DISPLAY INVISIBLE (2523 3625);
FORCEADD TAP..1
(2525 3725);
FORCEPROP 3 LASTPIN (2475 3725) SIG_NAME M_E_CPU0_SA_DQS_DP<5>
J 0
(2485 3735);
DISPLAY 0.659574 (2485 3735);
PAINT MONO (2485 3735);
DISPLAY INVISIBLE (2485 3735);
FORCEPROP 1 LASTPIN (2475 3725) BN 5
J 0
(2463 3733);
DISPLAY 0.680851 (2463 3733);
PAINT GREEN (2463 3733);
FORCEPROP 2 LAST CDS_LIB standard
J 0
(2525 3725);
DISPLAY INVISIBLE (2525 3725);
FORCEPROP 1 LAST BODY_TYPE PLUMBING
J 0
(2525 3775);
DISPLAY 0.872340 (2525 3775);
PAINT GREEN (2525 3775);
DISPLAY INVISIBLE (2525 3775);
FORCEPROP 1 LAST HDL_TAP TRUE
J 0
(2850 3600);
DISPLAY 0.872340 (2850 3600);
DISPLAY INVISIBLE (2850 3600);
FORCEPROP 1 LAST PATH I143
J 0
(2523 3725);
DISPLAY 0.872340 (2523 3725);
PAINT GREEN (2523 3725);
DISPLAY INVISIBLE (2523 3725);
FORCEADD TAP..1
(2525 3825);
FORCEPROP 3 LASTPIN (2475 3825) SIG_NAME M_E_CPU0_SA_DQS_DP<6>
J 0
(2485 3835);
DISPLAY 0.659574 (2485 3835);
PAINT MONO (2485 3835);
DISPLAY INVISIBLE (2485 3835);
FORCEPROP 1 LASTPIN (2475 3825) BN 6
J 0
(2463 3833);
DISPLAY 0.680851 (2463 3833);
PAINT GREEN (2463 3833);
FORCEPROP 2 LAST CDS_LIB standard
J 0
(2525 3825);
DISPLAY INVISIBLE (2525 3825);
FORCEPROP 1 LAST BODY_TYPE PLUMBING
J 0
(2525 3875);
DISPLAY 0.872340 (2525 3875);
PAINT GREEN (2525 3875);
DISPLAY INVISIBLE (2525 3875);
FORCEPROP 1 LAST HDL_TAP TRUE
J 0
(2850 3700);
DISPLAY 0.872340 (2850 3700);
DISPLAY INVISIBLE (2850 3700);
FORCEPROP 1 LAST PATH I144
J 0
(2523 3825);
DISPLAY 0.872340 (2523 3825);
PAINT GREEN (2523 3825);
DISPLAY INVISIBLE (2523 3825);
FORCEADD TAP..1
(2525 3925);
FORCEPROP 3 LASTPIN (2475 3925) SIG_NAME M_E_CPU0_SA_DQS_DP<7>
J 0
(2485 3935);
DISPLAY 0.659574 (2485 3935);
PAINT MONO (2485 3935);
DISPLAY INVISIBLE (2485 3935);
FORCEPROP 1 LASTPIN (2475 3925) BN 7
J 0
(2463 3933);
DISPLAY 0.680851 (2463 3933);
PAINT GREEN (2463 3933);
FORCEPROP 2 LAST CDS_LIB standard
J 0
(2525 3925);
DISPLAY INVISIBLE (2525 3925);
FORCEPROP 1 LAST BODY_TYPE PLUMBING
J 0
(2525 3975);
DISPLAY 0.872340 (2525 3975);
PAINT GREEN (2525 3975);
DISPLAY INVISIBLE (2525 3975);
FORCEPROP 1 LAST HDL_TAP TRUE
J 0
(2850 3800);
DISPLAY 0.872340 (2850 3800);
DISPLAY INVISIBLE (2850 3800);
FORCEPROP 1 LAST PATH I145
J 0
(2523 3925);
DISPLAY 0.872340 (2523 3925);
PAINT GREEN (2523 3925);
DISPLAY INVISIBLE (2523 3925);
FORCEADD Q_CAP..1
(3125 250);
FORCEPROP 1 LAST PART_NUMBER CH6103KEA00
J 0
(3175 100);
DISPLAY 0.978723 (3175 100);
DISPLAY INVISIBLE (3175 100);
FORCEPROP 1 LAST TOLERANCE 10%
J 0
(3175 200);
DISPLAY 0.978723 (3175 200);
FORCEPROP 1 LAST VOLTAGE 16V
J 0
(3175 250);
DISPLAY 0.978723 (3175 250);
FORCEPROP 1 LAST VALUE 10UF
J 0
(3175 300);
DISPLAY 0.978723 (3175 300);
FORCEPROP 1 LAST PACK_TYPE C0805
J 0
(3175 50);
DISPLAY 0.978723 (3175 50);
FORCEPROP 1 LAST MATERIAL X6S
J 0
(3175 150);
DISPLAY 0.978723 (3175 150);
FORCEPROP 1 LAST $LOCATION C31
J 0
(3175 350);
DISPLAY 0.978723 (3175 350);
FORCEPROP 1 LASTPIN (3125 350) $PN 1
J 0
(3135 330);
DISPLAY 0.787234 (3135 330);
FORCEPROP 1 LASTPIN (3125 150) $PN 2
J 0
(3135 130);
DISPLAY 0.787234 (3135 130);
FORCEPROP 2 LAST CDS_LIB pure_quanta
J 0
(3125 250);
PAINT MONO (3125 250);
DISPLAY INVISIBLE (3125 250);
FORCEPROP 2 LAST CDS_LOCATION C31
J 0
(3175 450);
DISPLAY 1.021277 (3175 450);
DISPLAY INVISIBLE (3175 450);
FORCEPROP 2 LAST $SEC 1
J 0
(3175 450);
DISPLAY 0.680851 (3175 450);
PAINT MONO (3175 450);
DISPLAY INVISIBLE (3175 450);
FORCEPROP 2 LAST CDS_SEC 1
J 0
(3175 450);
DISPLAY 1.021277 (3175 450);
DISPLAY INVISIBLE (3175 450);
FORCEPROP 1 LAST PATH I146
J 0
(3175 400);
DISPLAY 0.978723 (3175 400);
PAINT WHITE (3175 400);
DISPLAY INVISIBLE (3175 400);
FORCEADD UNIVERSAL_GND..1
(4200 425);
FORCEPROP 3 LASTPIN (4200 475) SIG_NAME GND\g
J 0
(4210 485);
DISPLAY 0.659574 (4210 485);
PAINT MONO (4210 485);
DISPLAY INVISIBLE (4210 485);
FORCEPROP 2 LAST CDS_LIB logical_power
J 0
(4200 425);
PAINT MONO (4200 425);
DISPLAY INVISIBLE (4200 425);
FORCEPROP 1 LAST HDL_POWER GND
J 1
(4225 350);
DISPLAY 0.872340 (4225 350);
PAINT GREEN (4225 350);
DISPLAY INVISIBLE (4225 350);
FORCEPROP 1 LAST PATH I147
J 0
(4275 425);
DISPLAY 0.872340 (4275 425);
PAINT AQUA (4275 425);
DISPLAY INVISIBLE (4275 425);
FORCEADD SCONN288_ADR50017P087CC..3
(5050 2500);
FORCEPROP 1 LAST PART_NUMBER DFHST8FS460
J 0
(4595 4424);
DISPLAY 0.723404 (4595 4424);
PAINT GREEN (4595 4424);
DISPLAY INVISIBLE (4595 4424);
FORCEPROP 1 LAST MATERIAL IO
J 0
(4595 4297);
DISPLAY 0.723404 (4595 4297);
PAINT GREEN (4595 4297);
FORCEPROP 2 LAST PART_TYPE SMLF
J 0
(4600 4575);
DISPLAY 1.021277 (4600 4575);
FORCEPROP 2 LAST VALUE SCONN288_ADR50017-P087CC
J 0
(4600 4525);
DISPLAY 1.021277 (4600 4525);
FORCEPROP 1 LAST $LOCATION J10
J 0
(4600 4475);
DISPLAY 0.723404 (4600 4475);
PAINT GREEN (4600 4475);
FORCEPROP 0 LASTPIN (5650 875) $PN G1
J 0
(5660 885);
DISPLAY 0.680851 (5660 885);
PAINT MONO (5660 885);
FORCEPROP 0 LASTPIN (5650 825) $PN G2
J 0
(5660 835);
DISPLAY 0.680851 (5660 835);
PAINT MONO (5660 835);
FORCEPROP 0 LASTPIN (5650 775) $PN G3
J 0
(5660 785);
DISPLAY 0.680851 (5660 785);
PAINT MONO (5660 785);
FORCEPROP 0 LASTPIN (4450 4025) $PN 1
J 2
(4440 4035);
DISPLAY 0.680851 (4440 4035);
PAINT MONO (4440 4035);
FORCEPROP 0 LASTPIN (4450 4075) $PN 145
J 2
(4440 4085);
DISPLAY 0.680851 (4440 4085);
PAINT MONO (4440 4085);
FORCEPROP 0 LASTPIN (4450 4125) $PN 146
J 2
(4440 4135);
DISPLAY 0.680851 (4440 4135);
PAINT MONO (4440 4135);
FORCEPROP 0 LASTPIN (5650 975) $PN 6
J 0
(5660 985);
DISPLAY 0.680851 (5660 985);
PAINT MONO (5660 985);
FORCEPROP 0 LASTPIN (5650 1025) $PN 8
J 0
(5660 1035);
DISPLAY 0.680851 (5660 1035);
PAINT MONO (5660 1035);
FORCEPROP 0 LASTPIN (5650 1075) $PN 10
J 0
(5660 1085);
DISPLAY 0.680851 (5660 1085);
PAINT MONO (5660 1085);
FORCEPROP 0 LASTPIN (5650 1125) $PN 13
J 0
(5660 1135);
DISPLAY 0.680851 (5660 1135);
PAINT MONO (5660 1135);
FORCEPROP 0 LASTPIN (5650 1175) $PN 15
J 0
(5660 1185);
DISPLAY 0.680851 (5660 1185);
PAINT MONO (5660 1185);
FORCEPROP 0 LASTPIN (5650 1225) $PN 17
J 0
(5660 1235);
DISPLAY 0.680851 (5660 1235);
PAINT MONO (5660 1235);
FORCEPROP 0 LASTPIN (5650 1275) $PN 19
J 0
(5660 1285);
DISPLAY 0.680851 (5660 1285);
PAINT MONO (5660 1285);
FORCEPROP 0 LASTPIN (5650 1325) $PN 21
J 0
(5660 1335);
DISPLAY 0.680851 (5660 1335);
PAINT MONO (5660 1335);
FORCEPROP 0 LASTPIN (5650 1375) $PN 24
J 0
(5660 1385);
DISPLAY 0.680851 (5660 1385);
PAINT MONO (5660 1385);
FORCEPROP 0 LASTPIN (5650 1425) $PN 26
J 0
(5660 1435);
DISPLAY 0.680851 (5660 1435);
PAINT MONO (5660 1435);
FORCEPROP 0 LASTPIN (5650 1475) $PN 28
J 0
(5660 1485);
DISPLAY 0.680851 (5660 1485);
PAINT MONO (5660 1485);
FORCEPROP 0 LASTPIN (5650 1525) $PN 30
J 0
(5660 1535);
DISPLAY 0.680851 (5660 1535);
PAINT MONO (5660 1535);
FORCEPROP 0 LASTPIN (5650 1575) $PN 32
J 0
(5660 1585);
DISPLAY 0.680851 (5660 1585);
PAINT MONO (5660 1585);
FORCEPROP 0 LASTPIN (5650 1625) $PN 35
J 0
(5660 1635);
DISPLAY 0.680851 (5660 1635);
PAINT MONO (5660 1635);
FORCEPROP 0 LASTPIN (5650 1675) $PN 37
J 0
(5660 1685);
DISPLAY 0.680851 (5660 1685);
PAINT MONO (5660 1685);
FORCEPROP 0 LASTPIN (5650 1725) $PN 39
J 0
(5660 1735);
DISPLAY 0.680851 (5660 1735);
PAINT MONO (5660 1735);
FORCEPROP 0 LASTPIN (5650 1775) $PN 41
J 0
(5660 1785);
DISPLAY 0.680851 (5660 1785);
PAINT MONO (5660 1785);
FORCEPROP 0 LASTPIN (5650 1825) $PN 43
J 0
(5660 1835);
DISPLAY 0.680851 (5660 1835);
PAINT MONO (5660 1835);
FORCEPROP 0 LASTPIN (5650 1875) $PN 46
J 0
(5660 1885);
DISPLAY 0.680851 (5660 1885);
PAINT MONO (5660 1885);
FORCEPROP 0 LASTPIN (5650 1925) $PN 48
J 0
(5660 1935);
DISPLAY 0.680851 (5660 1935);
PAINT MONO (5660 1935);
FORCEPROP 0 LASTPIN (5650 1975) $PN 50
J 0
(5660 1985);
DISPLAY 0.680851 (5660 1985);
PAINT MONO (5660 1985);
FORCEPROP 0 LASTPIN (5650 2025) $PN 52
J 0
(5660 2035);
DISPLAY 0.680851 (5660 2035);
PAINT MONO (5660 2035);
FORCEPROP 0 LASTPIN (5650 2075) $PN 54
J 0
(5660 2085);
DISPLAY 0.680851 (5660 2085);
PAINT MONO (5660 2085);
FORCEPROP 0 LASTPIN (5650 2125) $PN 57
J 0
(5660 2135);
DISPLAY 0.680851 (5660 2135);
PAINT MONO (5660 2135);
FORCEPROP 0 LASTPIN (5650 2175) $PN 59
J 0
(5660 2185);
DISPLAY 0.680851 (5660 2185);
PAINT MONO (5660 2185);
FORCEPROP 0 LASTPIN (5650 2225) $PN 61
J 0
(5660 2235);
DISPLAY 0.680851 (5660 2235);
PAINT MONO (5660 2235);
FORCEPROP 0 LASTPIN (5650 2275) $PN 63
J 0
(5660 2285);
DISPLAY 0.680851 (5660 2285);
PAINT MONO (5660 2285);
FORCEPROP 0 LASTPIN (5650 2325) $PN 65
J 0
(5660 2335);
DISPLAY 0.680851 (5660 2335);
PAINT MONO (5660 2335);
FORCEPROP 0 LASTPIN (5650 2375) $PN 67
J 0
(5660 2385);
DISPLAY 0.680851 (5660 2385);
PAINT MONO (5660 2385);
FORCEPROP 0 LASTPIN (5650 2425) $PN 69
J 0
(5660 2435);
DISPLAY 0.680851 (5660 2435);
PAINT MONO (5660 2435);
FORCEPROP 0 LASTPIN (5650 2475) $PN 71
J 0
(5660 2485);
DISPLAY 0.680851 (5660 2485);
PAINT MONO (5660 2485);
FORCEPROP 0 LASTPIN (5650 2525) $PN 73
J 0
(5660 2535);
DISPLAY 0.680851 (5660 2535);
PAINT MONO (5660 2535);
FORCEPROP 0 LASTPIN (5650 2575) $PN 75
J 0
(5660 2585);
DISPLAY 0.680851 (5660 2585);
PAINT MONO (5660 2585);
FORCEPROP 0 LASTPIN (5650 2625) $PN 77
J 0
(5660 2635);
DISPLAY 0.680851 (5660 2635);
PAINT MONO (5660 2635);
FORCEPROP 0 LASTPIN (5650 2675) $PN 79
J 0
(5660 2685);
DISPLAY 0.680851 (5660 2685);
PAINT MONO (5660 2685);
FORCEPROP 0 LASTPIN (5650 2725) $PN 81
J 0
(5660 2735);
DISPLAY 0.680851 (5660 2735);
PAINT MONO (5660 2735);
FORCEPROP 0 LASTPIN (5650 2775) $PN 83
J 0
(5660 2785);
DISPLAY 0.680851 (5660 2785);
PAINT MONO (5660 2785);
FORCEPROP 0 LASTPIN (5650 2825) $PN 85
J 0
(5660 2835);
DISPLAY 0.680851 (5660 2835);
PAINT MONO (5660 2835);
FORCEPROP 0 LASTPIN (5650 2875) $PN 88
J 0
(5660 2885);
DISPLAY 0.680851 (5660 2885);
PAINT MONO (5660 2885);
FORCEPROP 0 LASTPIN (5650 2925) $PN 90
J 0
(5660 2935);
DISPLAY 0.680851 (5660 2935);
PAINT MONO (5660 2935);
FORCEPROP 0 LASTPIN (5650 2975) $PN 92
J 0
(5660 2985);
DISPLAY 0.680851 (5660 2985);
PAINT MONO (5660 2985);
FORCEPROP 0 LASTPIN (5650 3025) $PN 95
J 0
(5660 3035);
DISPLAY 0.680851 (5660 3035);
PAINT MONO (5660 3035);
FORCEPROP 0 LASTPIN (5650 3075) $PN 97
J 0
(5660 3085);
DISPLAY 0.680851 (5660 3085);
PAINT MONO (5660 3085);
FORCEPROP 0 LASTPIN (5650 3125) $PN 99
J 0
(5660 3135);
DISPLAY 0.680851 (5660 3135);
PAINT MONO (5660 3135);
FORCEPROP 0 LASTPIN (5650 3175) $PN 101
J 0
(5660 3185);
DISPLAY 0.680851 (5660 3185);
PAINT MONO (5660 3185);
FORCEPROP 0 LASTPIN (5650 3225) $PN 103
J 0
(5660 3235);
DISPLAY 0.680851 (5660 3235);
PAINT MONO (5660 3235);
FORCEPROP 0 LASTPIN (5650 3275) $PN 106
J 0
(5660 3285);
DISPLAY 0.680851 (5660 3285);
PAINT MONO (5660 3285);
FORCEPROP 0 LASTPIN (5650 3325) $PN 108
J 0
(5660 3335);
DISPLAY 0.680851 (5660 3335);
PAINT MONO (5660 3335);
FORCEPROP 0 LASTPIN (5650 3375) $PN 110
J 0
(5660 3385);
DISPLAY 0.680851 (5660 3385);
PAINT MONO (5660 3385);
FORCEPROP 0 LASTPIN (5650 3425) $PN 112
J 0
(5660 3435);
DISPLAY 0.680851 (5660 3435);
PAINT MONO (5660 3435);
FORCEPROP 0 LASTPIN (5650 3475) $PN 114
J 0
(5660 3485);
DISPLAY 0.680851 (5660 3485);
PAINT MONO (5660 3485);
FORCEPROP 0 LASTPIN (5650 3525) $PN 117
J 0
(5660 3535);
DISPLAY 0.680851 (5660 3535);
PAINT MONO (5660 3535);
FORCEPROP 0 LASTPIN (5650 3575) $PN 119
J 0
(5660 3585);
DISPLAY 0.680851 (5660 3585);
PAINT MONO (5660 3585);
FORCEPROP 0 LASTPIN (5650 3625) $PN 121
J 0
(5660 3635);
DISPLAY 0.680851 (5660 3635);
PAINT MONO (5660 3635);
FORCEPROP 0 LASTPIN (5650 3675) $PN 123
J 0
(5660 3685);
DISPLAY 0.680851 (5660 3685);
PAINT MONO (5660 3685);
FORCEPROP 0 LASTPIN (5650 3725) $PN 125
J 0
(5660 3735);
DISPLAY 0.680851 (5660 3735);
PAINT MONO (5660 3735);
FORCEPROP 0 LASTPIN (5650 3775) $PN 128
J 0
(5660 3785);
DISPLAY 0.680851 (5660 3785);
PAINT MONO (5660 3785);
FORCEPROP 0 LASTPIN (5650 3825) $PN 130
J 0
(5660 3835);
DISPLAY 0.680851 (5660 3835);
PAINT MONO (5660 3835);
FORCEPROP 0 LASTPIN (5650 3875) $PN 132
J 0
(5660 3885);
DISPLAY 0.680851 (5660 3885);
PAINT MONO (5660 3885);
FORCEPROP 0 LASTPIN (5650 3925) $PN 134
J 0
(5660 3935);
DISPLAY 0.680851 (5660 3935);
PAINT MONO (5660 3935);
FORCEPROP 0 LASTPIN (5650 3975) $PN 136
J 0
(5660 3985);
DISPLAY 0.680851 (5660 3985);
PAINT MONO (5660 3985);
FORCEPROP 0 LASTPIN (5650 4025) $PN 139
J 0
(5660 4035);
DISPLAY 0.680851 (5660 4035);
PAINT MONO (5660 4035);
FORCEPROP 0 LASTPIN (5650 4075) $PN 141
J 0
(5660 4085);
DISPLAY 0.680851 (5660 4085);
PAINT MONO (5660 4085);
FORCEPROP 0 LASTPIN (5650 4125) $PN 143
J 0
(5660 4135);
DISPLAY 0.680851 (5660 4135);
PAINT MONO (5660 4135);
FORCEPROP 0 LASTPIN (4450 875) $PN 151
J 2
(4440 885);
DISPLAY 0.680851 (4440 885);
PAINT MONO (4440 885);
FORCEPROP 0 LASTPIN (4450 925) $PN 153
J 2
(4440 935);
DISPLAY 0.680851 (4440 935);
PAINT MONO (4440 935);
FORCEPROP 0 LASTPIN (4450 975) $PN 155
J 2
(4440 985);
DISPLAY 0.680851 (4440 985);
PAINT MONO (4440 985);
FORCEPROP 0 LASTPIN (4450 1025) $PN 158
J 2
(4440 1035);
DISPLAY 0.680851 (4440 1035);
PAINT MONO (4440 1035);
FORCEPROP 0 LASTPIN (4450 1075) $PN 160
J 2
(4440 1085);
DISPLAY 0.680851 (4440 1085);
PAINT MONO (4440 1085);
FORCEPROP 0 LASTPIN (4450 1125) $PN 162
J 2
(4440 1135);
DISPLAY 0.680851 (4440 1135);
PAINT MONO (4440 1135);
FORCEPROP 0 LASTPIN (4450 1175) $PN 164
J 2
(4440 1185);
DISPLAY 0.680851 (4440 1185);
PAINT MONO (4440 1185);
FORCEPROP 0 LASTPIN (4450 1225) $PN 166
J 2
(4440 1235);
DISPLAY 0.680851 (4440 1235);
PAINT MONO (4440 1235);
FORCEPROP 0 LASTPIN (4450 1275) $PN 169
J 2
(4440 1285);
DISPLAY 0.680851 (4440 1285);
PAINT MONO (4440 1285);
FORCEPROP 0 LASTPIN (4450 1325) $PN 171
J 2
(4440 1335);
DISPLAY 0.680851 (4440 1335);
PAINT MONO (4440 1335);
FORCEPROP 0 LASTPIN (4450 1375) $PN 173
J 2
(4440 1385);
DISPLAY 0.680851 (4440 1385);
PAINT MONO (4440 1385);
FORCEPROP 0 LASTPIN (4450 1425) $PN 175
J 2
(4440 1435);
DISPLAY 0.680851 (4440 1435);
PAINT MONO (4440 1435);
FORCEPROP 0 LASTPIN (4450 1475) $PN 177
J 2
(4440 1485);
DISPLAY 0.680851 (4440 1485);
PAINT MONO (4440 1485);
FORCEPROP 0 LASTPIN (4450 1525) $PN 180
J 2
(4440 1535);
DISPLAY 0.680851 (4440 1535);
PAINT MONO (4440 1535);
FORCEPROP 0 LASTPIN (4450 1575) $PN 182
J 2
(4440 1585);
DISPLAY 0.680851 (4440 1585);
PAINT MONO (4440 1585);
FORCEPROP 0 LASTPIN (4450 1625) $PN 184
J 2
(4440 1635);
DISPLAY 0.680851 (4440 1635);
PAINT MONO (4440 1635);
FORCEPROP 0 LASTPIN (4450 1675) $PN 186
J 2
(4440 1685);
DISPLAY 0.680851 (4440 1685);
PAINT MONO (4440 1685);
FORCEPROP 0 LASTPIN (4450 1725) $PN 188
J 2
(4440 1735);
DISPLAY 0.680851 (4440 1735);
PAINT MONO (4440 1735);
FORCEPROP 0 LASTPIN (4450 1775) $PN 191
J 2
(4440 1785);
DISPLAY 0.680851 (4440 1785);
PAINT MONO (4440 1785);
FORCEPROP 0 LASTPIN (4450 1825) $PN 193
J 2
(4440 1835);
DISPLAY 0.680851 (4440 1835);
PAINT MONO (4440 1835);
FORCEPROP 0 LASTPIN (4450 1875) $PN 195
J 2
(4440 1885);
DISPLAY 0.680851 (4440 1885);
PAINT MONO (4440 1885);
FORCEPROP 0 LASTPIN (4450 1925) $PN 197
J 2
(4440 1935);
DISPLAY 0.680851 (4440 1935);
PAINT MONO (4440 1935);
FORCEPROP 0 LASTPIN (4450 1975) $PN 199
J 2
(4440 1985);
DISPLAY 0.680851 (4440 1985);
PAINT MONO (4440 1985);
FORCEPROP 0 LASTPIN (4450 2025) $PN 202
J 2
(4440 2035);
DISPLAY 0.680851 (4440 2035);
PAINT MONO (4440 2035);
FORCEPROP 0 LASTPIN (4450 2075) $PN 204
J 2
(4440 2085);
DISPLAY 0.680851 (4440 2085);
PAINT MONO (4440 2085);
FORCEPROP 0 LASTPIN (4450 2125) $PN 206
J 2
(4440 2135);
DISPLAY 0.680851 (4440 2135);
PAINT MONO (4440 2135);
FORCEPROP 0 LASTPIN (4450 2175) $PN 208
J 2
(4440 2185);
DISPLAY 0.680851 (4440 2185);
PAINT MONO (4440 2185);
FORCEPROP 0 LASTPIN (4450 2225) $PN 210
J 2
(4440 2235);
DISPLAY 0.680851 (4440 2235);
PAINT MONO (4440 2235);
FORCEPROP 0 LASTPIN (4450 2275) $PN 212
J 2
(4440 2285);
DISPLAY 0.680851 (4440 2285);
PAINT MONO (4440 2285);
FORCEPROP 0 LASTPIN (4450 2325) $PN 214
J 2
(4440 2335);
DISPLAY 0.680851 (4440 2335);
PAINT MONO (4440 2335);
FORCEPROP 0 LASTPIN (4450 2375) $PN 216
J 2
(4440 2385);
DISPLAY 0.680851 (4440 2385);
PAINT MONO (4440 2385);
FORCEPROP 0 LASTPIN (4450 2425) $PN 219
J 2
(4440 2435);
DISPLAY 0.680851 (4440 2435);
PAINT MONO (4440 2435);
FORCEPROP 0 LASTPIN (4450 2475) $PN 222
J 2
(4440 2485);
DISPLAY 0.680851 (4440 2485);
PAINT MONO (4440 2485);
FORCEPROP 0 LASTPIN (4450 2525) $PN 224
J 2
(4440 2535);
DISPLAY 0.680851 (4440 2535);
PAINT MONO (4440 2535);
FORCEPROP 0 LASTPIN (4450 2575) $PN 226
J 2
(4440 2585);
DISPLAY 0.680851 (4440 2585);
PAINT MONO (4440 2585);
FORCEPROP 0 LASTPIN (4450 2625) $PN 228
J 2
(4440 2635);
DISPLAY 0.680851 (4440 2635);
PAINT MONO (4440 2635);
FORCEPROP 0 LASTPIN (4450 2675) $PN 230
J 2
(4440 2685);
DISPLAY 0.680851 (4440 2685);
PAINT MONO (4440 2685);
FORCEPROP 0 LASTPIN (4450 2725) $PN 233
J 2
(4440 2735);
DISPLAY 0.680851 (4440 2735);
PAINT MONO (4440 2735);
FORCEPROP 0 LASTPIN (4450 2775) $PN 235
J 2
(4440 2785);
DISPLAY 0.680851 (4440 2785);
PAINT MONO (4440 2785);
FORCEPROP 0 LASTPIN (4450 2825) $PN 237
J 2
(4440 2835);
DISPLAY 0.680851 (4440 2835);
PAINT MONO (4440 2835);
FORCEPROP 0 LASTPIN (4450 2875) $PN 240
J 2
(4440 2885);
DISPLAY 0.680851 (4440 2885);
PAINT MONO (4440 2885);
FORCEPROP 0 LASTPIN (4450 2925) $PN 242
J 2
(4440 2935);
DISPLAY 0.680851 (4440 2935);
PAINT MONO (4440 2935);
FORCEPROP 0 LASTPIN (4450 2975) $PN 244
J 2
(4440 2985);
DISPLAY 0.680851 (4440 2985);
PAINT MONO (4440 2985);
FORCEPROP 0 LASTPIN (4450 3025) $PN 246
J 2
(4440 3035);
DISPLAY 0.680851 (4440 3035);
PAINT MONO (4440 3035);
FORCEPROP 0 LASTPIN (4450 3075) $PN 248
J 2
(4440 3085);
DISPLAY 0.680851 (4440 3085);
PAINT MONO (4440 3085);
FORCEPROP 0 LASTPIN (4450 3125) $PN 251
J 2
(4440 3135);
DISPLAY 0.680851 (4440 3135);
PAINT MONO (4440 3135);
FORCEPROP 0 LASTPIN (4450 3175) $PN 253
J 2
(4440 3185);
DISPLAY 0.680851 (4440 3185);
PAINT MONO (4440 3185);
FORCEPROP 0 LASTPIN (4450 3225) $PN 255
J 2
(4440 3235);
DISPLAY 0.680851 (4440 3235);
PAINT MONO (4440 3235);
FORCEPROP 0 LASTPIN (4450 3275) $PN 257
J 2
(4440 3285);
DISPLAY 0.680851 (4440 3285);
PAINT MONO (4440 3285);
FORCEPROP 0 LASTPIN (4450 3325) $PN 259
J 2
(4440 3335);
DISPLAY 0.680851 (4440 3335);
PAINT MONO (4440 3335);
FORCEPROP 0 LASTPIN (4450 3375) $PN 262
J 2
(4440 3385);
DISPLAY 0.680851 (4440 3385);
PAINT MONO (4440 3385);
FORCEPROP 0 LASTPIN (4450 3425) $PN 264
J 2
(4440 3435);
DISPLAY 0.680851 (4440 3435);
PAINT MONO (4440 3435);
FORCEPROP 0 LASTPIN (4450 3475) $PN 266
J 2
(4440 3485);
DISPLAY 0.680851 (4440 3485);
PAINT MONO (4440 3485);
FORCEPROP 0 LASTPIN (4450 3525) $PN 268
J 2
(4440 3535);
DISPLAY 0.680851 (4440 3535);
PAINT MONO (4440 3535);
FORCEPROP 0 LASTPIN (4450 3575) $PN 270
J 2
(4440 3585);
DISPLAY 0.680851 (4440 3585);
PAINT MONO (4440 3585);
FORCEPROP 0 LASTPIN (4450 3625) $PN 273
J 2
(4440 3635);
DISPLAY 0.680851 (4440 3635);
PAINT MONO (4440 3635);
FORCEPROP 0 LASTPIN (4450 3675) $PN 275
J 2
(4440 3685);
DISPLAY 0.680851 (4440 3685);
PAINT MONO (4440 3685);
FORCEPROP 0 LASTPIN (4450 3725) $PN 277
J 2
(4440 3735);
DISPLAY 0.680851 (4440 3735);
PAINT MONO (4440 3735);
FORCEPROP 0 LASTPIN (4450 3775) $PN 279
J 2
(4440 3785);
DISPLAY 0.680851 (4440 3785);
PAINT MONO (4440 3785);
FORCEPROP 0 LASTPIN (4450 3825) $PN 281
J 2
(4440 3835);
DISPLAY 0.680851 (4440 3835);
PAINT MONO (4440 3835);
FORCEPROP 0 LASTPIN (4450 3875) $PN 284
J 2
(4440 3885);
DISPLAY 0.680851 (4440 3885);
PAINT MONO (4440 3885);
FORCEPROP 0 LASTPIN (4450 3925) $PN 286
J 2
(4440 3935);
DISPLAY 0.680851 (4440 3935);
PAINT MONO (4440 3935);
FORCEPROP 0 LASTPIN (4450 3975) $PN 288
J 2
(4440 3985);
DISPLAY 0.680851 (4440 3985);
PAINT MONO (4440 3985);
FORCEPROP 1 LAST NEEDS_NO_SIZE TRUE
J 0
(5050 2500);
DISPLAY 0.723404 (5050 2500);
PAINT GREEN (5050 2500);
DISPLAY INVISIBLE (5050 2500);
FORCEPROP 1 LAST CDS_LMAN_SYM_OUTLINE -450,1775,450,-1775
J 0
(5050 2500);
DISPLAY 0.468085 (5050 2500);
PAINT GREEN (5050 2500);
DISPLAY INVISIBLE (5050 2500);
FORCEPROP 2 LAST CDS_LIB pure_quanta
J 0
(5050 2500);
DISPLAY INVISIBLE (5050 2500);
FORCEPROP 2 LAST CDS_LOCATION J10
J 0
(4600 4625);
DISPLAY 1.021277 (4600 4625);
DISPLAY INVISIBLE (4600 4625);
FORCEPROP 0 LAST $SEC 3
J 0
(4600 4625);
DISPLAY 0.680851 (4600 4625);
PAINT MONO (4600 4625);
DISPLAY INVISIBLE (4600 4625);
FORCEPROP 2 LAST CDS_SEC 3
J 0
(4600 4625);
DISPLAY 1.021277 (4600 4625);
DISPLAY INVISIBLE (4600 4625);
FORCEPROP 1 LAST PATH I148
J 0
(5050 2500);
DISPLAY 0.723404 (5050 2500);
PAINT GREEN (5050 2500);
DISPLAY INVISIBLE (5050 2500);
FORCEADD TAP..1
(2700 2225);
FORCEPROP 3 LASTPIN (2650 2225) SIG_NAME M_E_CPU0_SB_DQS_DN<1>
J 0
(2660 2235);
DISPLAY 0.659574 (2660 2235);
PAINT MONO (2660 2235);
DISPLAY INVISIBLE (2660 2235);
FORCEPROP 1 LASTPIN (2650 2225) BN 1
J 0
(2638 2233);
DISPLAY 0.680851 (2638 2233);
PAINT GREEN (2638 2233);
FORCEPROP 2 LAST CDS_LIB standard
J 0
(2700 2225);
DISPLAY INVISIBLE (2700 2225);
FORCEPROP 1 LAST BODY_TYPE PLUMBING
J 0
(2700 2275);
DISPLAY 0.872340 (2700 2275);
PAINT GREEN (2700 2275);
DISPLAY INVISIBLE (2700 2275);
FORCEPROP 1 LAST HDL_TAP TRUE
J 0
(3025 2100);
DISPLAY 0.872340 (3025 2100);
DISPLAY INVISIBLE (3025 2100);
FORCEPROP 1 LAST PATH I149
J 0
(2698 2225);
DISPLAY 0.872340 (2698 2225);
PAINT GREEN (2698 2225);
DISPLAY INVISIBLE (2698 2225);
FORCEADD OFFPAGE..3
R 2
(-2800 2300);
FORCEPROP 2 LAST $XR1 90 
J 0
(-3139 2300);
DISPLAY 0.638298 (-3139 2300);
PAINT MONO (-3139 2300);
FORCEPROP 2 LAST $XR0 24 
J 0
(-3049 2300);
DISPLAY 0.638298 (-3049 2300);
PAINT MONO (-3049 2300);
FORCEPROP 2 LAST CDS_LIB standard
J 0
(-2800 2300);
PAINT MONO (-2800 2300);
DISPLAY INVISIBLE (-2800 2300);
FORCEPROP 1 LAST OFFPAGE TRUE
J 2
(-3125 2175);
DISPLAY 0.872340 (-3125 2175);
DISPLAY INVISIBLE (-3125 2175);
FORCEPROP 1 LAST COMMENT_BODY TRUE
J 2
(-2750 2200);
DISPLAY 0.872340 (-2750 2200);
PAINT GREEN (-2750 2200);
DISPLAY INVISIBLE (-2750 2200);
FORCEPROP 2 LAST PATH I15
J 0
(-2750 2375);
DISPLAY 1.021277 (-2750 2375);
DISPLAY INVISIBLE (-2750 2375);
FORCEADD TAP..1
(2700 2125);
FORCEPROP 3 LASTPIN (2650 2125) SIG_NAME M_E_CPU0_SB_DQS_DN<0>
J 0
(2660 2135);
DISPLAY 0.659574 (2660 2135);
PAINT MONO (2660 2135);
DISPLAY INVISIBLE (2660 2135);
FORCEPROP 1 LASTPIN (2650 2125) BN 0
J 0
(2638 2133);
DISPLAY 0.680851 (2638 2133);
PAINT GREEN (2638 2133);
FORCEPROP 2 LAST CDS_LIB standard
J 0
(2700 2125);
PAINT MONO (2700 2125);
DISPLAY INVISIBLE (2700 2125);
FORCEPROP 1 LAST BODY_TYPE PLUMBING
J 0
(2700 2175);
DISPLAY 0.872340 (2700 2175);
PAINT GREEN (2700 2175);
DISPLAY INVISIBLE (2700 2175);
FORCEPROP 1 LAST HDL_TAP TRUE
J 0
(3025 2000);
DISPLAY 0.872340 (3025 2000);
DISPLAY INVISIBLE (3025 2000);
FORCEPROP 1 LAST PATH I150
J 0
(2698 2125);
DISPLAY 0.872340 (2698 2125);
PAINT GREEN (2698 2125);
DISPLAY INVISIBLE (2698 2125);
FORCEADD TAP..1
(2700 2325);
FORCEPROP 3 LASTPIN (2650 2325) SIG_NAME M_E_CPU0_SB_DQS_DN<2>
J 0
(2660 2335);
DISPLAY 0.659574 (2660 2335);
PAINT MONO (2660 2335);
DISPLAY INVISIBLE (2660 2335);
FORCEPROP 1 LASTPIN (2650 2325) BN 2
J 0
(2638 2333);
DISPLAY 0.680851 (2638 2333);
PAINT GREEN (2638 2333);
FORCEPROP 2 LAST CDS_LIB standard
J 0
(2700 2325);
DISPLAY INVISIBLE (2700 2325);
FORCEPROP 1 LAST BODY_TYPE PLUMBING
J 0
(2700 2375);
DISPLAY 0.872340 (2700 2375);
PAINT GREEN (2700 2375);
DISPLAY INVISIBLE (2700 2375);
FORCEPROP 1 LAST HDL_TAP TRUE
J 0
(3025 2200);
DISPLAY 0.872340 (3025 2200);
DISPLAY INVISIBLE (3025 2200);
FORCEPROP 1 LAST PATH I151
J 0
(2698 2325);
DISPLAY 0.872340 (2698 2325);
PAINT GREEN (2698 2325);
DISPLAY INVISIBLE (2698 2325);
FORCEADD TAP..1
(2700 2425);
FORCEPROP 3 LASTPIN (2650 2425) SIG_NAME M_E_CPU0_SB_DQS_DN<3>
J 0
(2660 2435);
DISPLAY 0.659574 (2660 2435);
PAINT MONO (2660 2435);
DISPLAY INVISIBLE (2660 2435);
FORCEPROP 1 LASTPIN (2650 2425) BN 3
J 0
(2638 2433);
DISPLAY 0.680851 (2638 2433);
PAINT GREEN (2638 2433);
FORCEPROP 2 LAST CDS_LIB standard
J 0
(2700 2425);
PAINT MONO (2700 2425);
DISPLAY INVISIBLE (2700 2425);
FORCEPROP 1 LAST BODY_TYPE PLUMBING
J 0
(2700 2475);
DISPLAY 0.872340 (2700 2475);
PAINT GREEN (2700 2475);
DISPLAY INVISIBLE (2700 2475);
FORCEPROP 1 LAST HDL_TAP TRUE
J 0
(3025 2300);
DISPLAY 0.872340 (3025 2300);
DISPLAY INVISIBLE (3025 2300);
FORCEPROP 1 LAST PATH I152
J 0
(2698 2425);
DISPLAY 0.872340 (2698 2425);
PAINT GREEN (2698 2425);
DISPLAY INVISIBLE (2698 2425);
FORCEADD TAP..1
(2700 2525);
FORCEPROP 3 LASTPIN (2650 2525) SIG_NAME M_E_CPU0_SB_DQS_DN<4>
J 0
(2660 2535);
DISPLAY 0.659574 (2660 2535);
PAINT MONO (2660 2535);
DISPLAY INVISIBLE (2660 2535);
FORCEPROP 1 LASTPIN (2650 2525) BN 4
J 0
(2638 2533);
DISPLAY 0.680851 (2638 2533);
PAINT GREEN (2638 2533);
FORCEPROP 2 LAST CDS_LIB standard
J 0
(2700 2525);
PAINT MONO (2700 2525);
DISPLAY INVISIBLE (2700 2525);
FORCEPROP 1 LAST BODY_TYPE PLUMBING
J 0
(2700 2575);
DISPLAY 0.872340 (2700 2575);
PAINT GREEN (2700 2575);
DISPLAY INVISIBLE (2700 2575);
FORCEPROP 1 LAST HDL_TAP TRUE
J 0
(3025 2400);
DISPLAY 0.872340 (3025 2400);
DISPLAY INVISIBLE (3025 2400);
FORCEPROP 1 LAST PATH I153
J 0
(2698 2525);
DISPLAY 0.872340 (2698 2525);
PAINT GREEN (2698 2525);
DISPLAY INVISIBLE (2698 2525);
FORCEADD TAP..1
(2700 2625);
FORCEPROP 3 LASTPIN (2650 2625) SIG_NAME M_E_CPU0_SB_DQS_DN<5>
J 0
(2660 2635);
DISPLAY 0.659574 (2660 2635);
PAINT MONO (2660 2635);
DISPLAY INVISIBLE (2660 2635);
FORCEPROP 1 LASTPIN (2650 2625) BN 5
J 0
(2638 2633);
DISPLAY 0.680851 (2638 2633);
PAINT GREEN (2638 2633);
FORCEPROP 2 LAST CDS_LIB standard
J 0
(2700 2625);
DISPLAY INVISIBLE (2700 2625);
FORCEPROP 1 LAST BODY_TYPE PLUMBING
J 0
(2700 2675);
DISPLAY 0.872340 (2700 2675);
PAINT GREEN (2700 2675);
DISPLAY INVISIBLE (2700 2675);
FORCEPROP 1 LAST HDL_TAP TRUE
J 0
(3025 2500);
DISPLAY 0.872340 (3025 2500);
DISPLAY INVISIBLE (3025 2500);
FORCEPROP 1 LAST PATH I154
J 0
(2698 2625);
DISPLAY 0.872340 (2698 2625);
PAINT GREEN (2698 2625);
DISPLAY INVISIBLE (2698 2625);
FORCEADD TAP..1
(2700 2725);
FORCEPROP 3 LASTPIN (2650 2725) SIG_NAME M_E_CPU0_SB_DQS_DN<6>
J 0
(2660 2735);
DISPLAY 0.659574 (2660 2735);
PAINT MONO (2660 2735);
DISPLAY INVISIBLE (2660 2735);
FORCEPROP 1 LASTPIN (2650 2725) BN 6
J 0
(2638 2733);
DISPLAY 0.680851 (2638 2733);
PAINT GREEN (2638 2733);
FORCEPROP 2 LAST CDS_LIB standard
J 0
(2700 2725);
DISPLAY INVISIBLE (2700 2725);
FORCEPROP 1 LAST BODY_TYPE PLUMBING
J 0
(2700 2775);
DISPLAY 0.872340 (2700 2775);
PAINT GREEN (2700 2775);
DISPLAY INVISIBLE (2700 2775);
FORCEPROP 1 LAST HDL_TAP TRUE
J 0
(3025 2600);
DISPLAY 0.872340 (3025 2600);
DISPLAY INVISIBLE (3025 2600);
FORCEPROP 1 LAST PATH I155
J 0
(2698 2725);
DISPLAY 0.872340 (2698 2725);
PAINT GREEN (2698 2725);
DISPLAY INVISIBLE (2698 2725);
FORCEADD TAP..1
(2700 2825);
FORCEPROP 3 LASTPIN (2650 2825) SIG_NAME M_E_CPU0_SB_DQS_DN<7>
J 0
(2660 2835);
DISPLAY 0.659574 (2660 2835);
PAINT MONO (2660 2835);
DISPLAY INVISIBLE (2660 2835);
FORCEPROP 1 LASTPIN (2650 2825) BN 7
J 0
(2638 2833);
DISPLAY 0.680851 (2638 2833);
PAINT GREEN (2638 2833);
FORCEPROP 2 LAST CDS_LIB standard
J 0
(2700 2825);
DISPLAY INVISIBLE (2700 2825);
FORCEPROP 1 LAST BODY_TYPE PLUMBING
J 0
(2700 2875);
DISPLAY 0.872340 (2700 2875);
PAINT GREEN (2700 2875);
DISPLAY INVISIBLE (2700 2875);
FORCEPROP 1 LAST HDL_TAP TRUE
J 0
(3025 2700);
DISPLAY 0.872340 (3025 2700);
DISPLAY INVISIBLE (3025 2700);
FORCEPROP 1 LAST PATH I156
J 0
(2698 2825);
DISPLAY 0.872340 (2698 2825);
PAINT GREEN (2698 2825);
DISPLAY INVISIBLE (2698 2825);
FORCEADD TAP..1
(2700 2925);
FORCEPROP 3 LASTPIN (2650 2925) SIG_NAME M_E_CPU0_SB_DQS_DN<8>
J 0
(2660 2935);
DISPLAY 0.659574 (2660 2935);
PAINT MONO (2660 2935);
DISPLAY INVISIBLE (2660 2935);
FORCEPROP 1 LASTPIN (2650 2925) BN 8
J 0
(2638 2933);
DISPLAY 0.680851 (2638 2933);
PAINT GREEN (2638 2933);
FORCEPROP 2 LAST CDS_LIB standard
J 0
(2700 2925);
DISPLAY INVISIBLE (2700 2925);
FORCEPROP 1 LAST BODY_TYPE PLUMBING
J 0
(2700 2975);
DISPLAY 0.872340 (2700 2975);
PAINT GREEN (2700 2975);
DISPLAY INVISIBLE (2700 2975);
FORCEPROP 1 LAST HDL_TAP TRUE
J 0
(3025 2800);
DISPLAY 0.872340 (3025 2800);
DISPLAY INVISIBLE (3025 2800);
FORCEPROP 1 LAST PATH I157
J 0
(2698 2925);
DISPLAY 0.872340 (2698 2925);
PAINT GREEN (2698 2925);
DISPLAY INVISIBLE (2698 2925);
FORCEADD TAP..1
(2700 3025);
FORCEPROP 3 LASTPIN (2650 3025) SIG_NAME M_E_CPU0_SB_DQS_DN<9>
J 0
(2660 3035);
DISPLAY 0.659574 (2660 3035);
PAINT MONO (2660 3035);
DISPLAY INVISIBLE (2660 3035);
FORCEPROP 1 LASTPIN (2650 3025) BN 9
J 0
(2638 3033);
DISPLAY 0.680851 (2638 3033);
PAINT GREEN (2638 3033);
FORCEPROP 2 LAST CDS_LIB standard
J 0
(2700 3025);
DISPLAY INVISIBLE (2700 3025);
FORCEPROP 1 LAST BODY_TYPE PLUMBING
J 0
(2700 3075);
DISPLAY 0.872340 (2700 3075);
PAINT GREEN (2700 3075);
DISPLAY INVISIBLE (2700 3075);
FORCEPROP 1 LAST HDL_TAP TRUE
J 0
(3025 2900);
DISPLAY 0.872340 (3025 2900);
DISPLAY INVISIBLE (3025 2900);
FORCEPROP 1 LAST PATH I158
J 0
(2698 3025);
DISPLAY 0.872340 (2698 3025);
PAINT GREEN (2698 3025);
DISPLAY INVISIBLE (2698 3025);
FORCEADD TAP..1
(2700 3175);
FORCEPROP 3 LASTPIN (2650 3175) SIG_NAME M_E_CPU0_SA_DQS_DN<0>
J 0
(2660 3185);
DISPLAY 0.659574 (2660 3185);
PAINT MONO (2660 3185);
DISPLAY INVISIBLE (2660 3185);
FORCEPROP 1 LASTPIN (2650 3175) BN 0
J 0
(2638 3183);
DISPLAY 0.680851 (2638 3183);
PAINT GREEN (2638 3183);
FORCEPROP 2 LAST CDS_LIB standard
J 0
(2700 3175);
PAINT MONO (2700 3175);
DISPLAY INVISIBLE (2700 3175);
FORCEPROP 1 LAST BODY_TYPE PLUMBING
J 0
(2700 3225);
DISPLAY 0.872340 (2700 3225);
PAINT GREEN (2700 3225);
DISPLAY INVISIBLE (2700 3225);
FORCEPROP 1 LAST HDL_TAP TRUE
J 0
(3025 3050);
DISPLAY 0.872340 (3025 3050);
DISPLAY INVISIBLE (3025 3050);
FORCEPROP 1 LAST PATH I159
J 0
(2698 3175);
DISPLAY 0.872340 (2698 3175);
PAINT GREEN (2698 3175);
DISPLAY INVISIBLE (2698 3175);
FORCEADD OFFPAGE..3
R 2
(-2800 2750);
FORCEPROP 2 LAST $XR1 90 
J 0
(-3139 2750);
DISPLAY 0.638298 (-3139 2750);
PAINT MONO (-3139 2750);
FORCEPROP 2 LAST $XR0 24 
J 0
(-3049 2750);
DISPLAY 0.638298 (-3049 2750);
PAINT MONO (-3049 2750);
FORCEPROP 2 LAST CDS_LIB standard
J 0
(-2800 2750);
PAINT MONO (-2800 2750);
DISPLAY INVISIBLE (-2800 2750);
FORCEPROP 1 LAST OFFPAGE TRUE
J 2
(-3125 2625);
DISPLAY 0.872340 (-3125 2625);
DISPLAY INVISIBLE (-3125 2625);
FORCEPROP 1 LAST COMMENT_BODY TRUE
J 2
(-2750 2650);
DISPLAY 0.872340 (-2750 2650);
PAINT GREEN (-2750 2650);
DISPLAY INVISIBLE (-2750 2650);
FORCEPROP 2 LAST PATH I16
J 0
(-2750 2825);
DISPLAY 1.021277 (-2750 2825);
DISPLAY INVISIBLE (-2750 2825);
FORCEADD TAP..1
(2700 3375);
FORCEPROP 3 LASTPIN (2650 3375) SIG_NAME M_E_CPU0_SA_DQS_DN<2>
J 0
(2660 3385);
DISPLAY 0.659574 (2660 3385);
PAINT MONO (2660 3385);
DISPLAY INVISIBLE (2660 3385);
FORCEPROP 1 LASTPIN (2650 3375) BN 2
J 0
(2638 3383);
DISPLAY 0.680851 (2638 3383);
PAINT GREEN (2638 3383);
FORCEPROP 2 LAST CDS_LIB standard
J 0
(2700 3375);
DISPLAY INVISIBLE (2700 3375);
FORCEPROP 1 LAST BODY_TYPE PLUMBING
J 0
(2700 3425);
DISPLAY 0.872340 (2700 3425);
PAINT GREEN (2700 3425);
DISPLAY INVISIBLE (2700 3425);
FORCEPROP 1 LAST HDL_TAP TRUE
J 0
(3025 3250);
DISPLAY 0.872340 (3025 3250);
DISPLAY INVISIBLE (3025 3250);
FORCEPROP 1 LAST PATH I160
J 0
(2698 3375);
DISPLAY 0.872340 (2698 3375);
PAINT GREEN (2698 3375);
DISPLAY INVISIBLE (2698 3375);
FORCEADD TAP..1
(2700 3275);
FORCEPROP 3 LASTPIN (2650 3275) SIG_NAME M_E_CPU0_SA_DQS_DN<1>
J 0
(2660 3285);
DISPLAY 0.659574 (2660 3285);
PAINT MONO (2660 3285);
DISPLAY INVISIBLE (2660 3285);
FORCEPROP 1 LASTPIN (2650 3275) BN 1
J 0
(2638 3283);
DISPLAY 0.680851 (2638 3283);
PAINT GREEN (2638 3283);
FORCEPROP 2 LAST CDS_LIB standard
J 0
(2700 3275);
DISPLAY INVISIBLE (2700 3275);
FORCEPROP 1 LAST BODY_TYPE PLUMBING
J 0
(2700 3325);
DISPLAY 0.872340 (2700 3325);
PAINT GREEN (2700 3325);
DISPLAY INVISIBLE (2700 3325);
FORCEPROP 1 LAST HDL_TAP TRUE
J 0
(3025 3150);
DISPLAY 0.872340 (3025 3150);
DISPLAY INVISIBLE (3025 3150);
FORCEPROP 1 LAST PATH I161
J 0
(2698 3275);
DISPLAY 0.872340 (2698 3275);
PAINT GREEN (2698 3275);
DISPLAY INVISIBLE (2698 3275);
FORCEADD TAP..1
(2700 3475);
FORCEPROP 3 LASTPIN (2650 3475) SIG_NAME M_E_CPU0_SA_DQS_DN<3>
J 0
(2660 3485);
DISPLAY 0.659574 (2660 3485);
PAINT MONO (2660 3485);
DISPLAY INVISIBLE (2660 3485);
FORCEPROP 1 LASTPIN (2650 3475) BN 3
J 0
(2638 3483);
DISPLAY 0.680851 (2638 3483);
PAINT GREEN (2638 3483);
FORCEPROP 2 LAST CDS_LIB standard
J 0
(2700 3475);
PAINT MONO (2700 3475);
DISPLAY INVISIBLE (2700 3475);
FORCEPROP 1 LAST BODY_TYPE PLUMBING
J 0
(2700 3525);
DISPLAY 0.872340 (2700 3525);
PAINT GREEN (2700 3525);
DISPLAY INVISIBLE (2700 3525);
FORCEPROP 1 LAST HDL_TAP TRUE
J 0
(3025 3350);
DISPLAY 0.872340 (3025 3350);
DISPLAY INVISIBLE (3025 3350);
FORCEPROP 1 LAST PATH I162
J 0
(2698 3475);
DISPLAY 0.872340 (2698 3475);
PAINT GREEN (2698 3475);
DISPLAY INVISIBLE (2698 3475);
FORCEADD TAP..1
(2700 3575);
FORCEPROP 3 LASTPIN (2650 3575) SIG_NAME M_E_CPU0_SA_DQS_DN<4>
J 0
(2660 3585);
DISPLAY 0.659574 (2660 3585);
PAINT MONO (2660 3585);
DISPLAY INVISIBLE (2660 3585);
FORCEPROP 1 LASTPIN (2650 3575) BN 4
J 0
(2638 3583);
DISPLAY 0.680851 (2638 3583);
PAINT GREEN (2638 3583);
FORCEPROP 2 LAST CDS_LIB standard
J 0
(2700 3575);
PAINT MONO (2700 3575);
DISPLAY INVISIBLE (2700 3575);
FORCEPROP 1 LAST BODY_TYPE PLUMBING
J 0
(2700 3625);
DISPLAY 0.872340 (2700 3625);
PAINT GREEN (2700 3625);
DISPLAY INVISIBLE (2700 3625);
FORCEPROP 1 LAST HDL_TAP TRUE
J 0
(3025 3450);
DISPLAY 0.872340 (3025 3450);
DISPLAY INVISIBLE (3025 3450);
FORCEPROP 1 LAST PATH I163
J 0
(2698 3575);
DISPLAY 0.872340 (2698 3575);
PAINT GREEN (2698 3575);
DISPLAY INVISIBLE (2698 3575);
FORCEADD TAP..1
(2700 3675);
FORCEPROP 3 LASTPIN (2650 3675) SIG_NAME M_E_CPU0_SA_DQS_DN<5>
J 0
(2660 3685);
DISPLAY 0.659574 (2660 3685);
PAINT MONO (2660 3685);
DISPLAY INVISIBLE (2660 3685);
FORCEPROP 1 LASTPIN (2650 3675) BN 5
J 0
(2638 3683);
DISPLAY 0.680851 (2638 3683);
PAINT GREEN (2638 3683);
FORCEPROP 2 LAST CDS_LIB standard
J 0
(2700 3675);
DISPLAY INVISIBLE (2700 3675);
FORCEPROP 1 LAST BODY_TYPE PLUMBING
J 0
(2700 3725);
DISPLAY 0.872340 (2700 3725);
PAINT GREEN (2700 3725);
DISPLAY INVISIBLE (2700 3725);
FORCEPROP 1 LAST HDL_TAP TRUE
J 0
(3025 3550);
DISPLAY 0.872340 (3025 3550);
DISPLAY INVISIBLE (3025 3550);
FORCEPROP 1 LAST PATH I164
J 0
(2698 3675);
DISPLAY 0.872340 (2698 3675);
PAINT GREEN (2698 3675);
DISPLAY INVISIBLE (2698 3675);
FORCEADD TAP..1
(2700 3875);
FORCEPROP 3 LASTPIN (2650 3875) SIG_NAME M_E_CPU0_SA_DQS_DN<7>
J 0
(2660 3885);
DISPLAY 0.659574 (2660 3885);
PAINT MONO (2660 3885);
DISPLAY INVISIBLE (2660 3885);
FORCEPROP 1 LASTPIN (2650 3875) BN 7
J 0
(2638 3883);
DISPLAY 0.680851 (2638 3883);
PAINT GREEN (2638 3883);
FORCEPROP 2 LAST CDS_LIB standard
J 0
(2700 3875);
DISPLAY INVISIBLE (2700 3875);
FORCEPROP 1 LAST BODY_TYPE PLUMBING
J 0
(2700 3925);
DISPLAY 0.872340 (2700 3925);
PAINT GREEN (2700 3925);
DISPLAY INVISIBLE (2700 3925);
FORCEPROP 1 LAST HDL_TAP TRUE
J 0
(3025 3750);
DISPLAY 0.872340 (3025 3750);
DISPLAY INVISIBLE (3025 3750);
FORCEPROP 1 LAST PATH I165
J 0
(2698 3875);
DISPLAY 0.872340 (2698 3875);
PAINT GREEN (2698 3875);
DISPLAY INVISIBLE (2698 3875);
FORCEADD TAP..1
(2700 3775);
FORCEPROP 3 LASTPIN (2650 3775) SIG_NAME M_E_CPU0_SA_DQS_DN<6>
J 0
(2660 3785);
DISPLAY 0.659574 (2660 3785);
PAINT MONO (2660 3785);
DISPLAY INVISIBLE (2660 3785);
FORCEPROP 1 LASTPIN (2650 3775) BN 6
J 0
(2638 3783);
DISPLAY 0.680851 (2638 3783);
PAINT GREEN (2638 3783);
FORCEPROP 2 LAST CDS_LIB standard
J 0
(2700 3775);
DISPLAY INVISIBLE (2700 3775);
FORCEPROP 1 LAST BODY_TYPE PLUMBING
J 0
(2700 3825);
DISPLAY 0.872340 (2700 3825);
PAINT GREEN (2700 3825);
DISPLAY INVISIBLE (2700 3825);
FORCEPROP 1 LAST HDL_TAP TRUE
J 0
(3025 3650);
DISPLAY 0.872340 (3025 3650);
DISPLAY INVISIBLE (3025 3650);
FORCEPROP 1 LAST PATH I166
J 0
(2698 3775);
DISPLAY 0.872340 (2698 3775);
PAINT GREEN (2698 3775);
DISPLAY INVISIBLE (2698 3775);
FORCEADD TAP..1
(2700 3975);
FORCEPROP 3 LASTPIN (2650 3975) SIG_NAME M_E_CPU0_SA_DQS_DN<8>
J 0
(2660 3985);
DISPLAY 0.659574 (2660 3985);
PAINT MONO (2660 3985);
DISPLAY INVISIBLE (2660 3985);
FORCEPROP 1 LASTPIN (2650 3975) BN 8
J 0
(2638 3983);
DISPLAY 0.680851 (2638 3983);
PAINT GREEN (2638 3983);
FORCEPROP 2 LAST CDS_LIB standard
J 0
(2700 3975);
DISPLAY INVISIBLE (2700 3975);
FORCEPROP 1 LAST BODY_TYPE PLUMBING
J 0
(2700 4025);
DISPLAY 0.872340 (2700 4025);
PAINT GREEN (2700 4025);
DISPLAY INVISIBLE (2700 4025);
FORCEPROP 1 LAST HDL_TAP TRUE
J 0
(3025 3850);
DISPLAY 0.872340 (3025 3850);
DISPLAY INVISIBLE (3025 3850);
FORCEPROP 1 LAST PATH I167
J 0
(2698 3975);
DISPLAY 0.872340 (2698 3975);
PAINT GREEN (2698 3975);
DISPLAY INVISIBLE (2698 3975);
FORCEADD OFFPAGE..2
(3650 3100);
FORCEPROP 2 LAST $XR1 90 
J 0
(3929 3100);
DISPLAY 0.638298 (3929 3100);
PAINT MONO (3929 3100);
FORCEPROP 2 LAST $XR0 24 
J 0
(3839 3100);
DISPLAY 0.638298 (3839 3100);
PAINT MONO (3839 3100);
FORCEPROP 2 LAST CDS_LIB standard
J 0
(3650 3100);
PAINT MONO (3650 3100);
DISPLAY INVISIBLE (3650 3100);
FORCEPROP 1 LAST OFFPAGE TRUE
J 0
(3975 2975);
DISPLAY 1.170213 (3975 2975);
PAINT GREEN (3975 2975);
DISPLAY INVISIBLE (3975 2975);
FORCEPROP 1 LAST COMMENT_BODY TRUE
J 0
(3605 3005);
DISPLAY 1.170213 (3605 3005);
PAINT GREEN (3605 3005);
DISPLAY INVISIBLE (3605 3005);
FORCEPROP 2 LAST PATH I168
J 0
(3825 3175);
DISPLAY 1.021277 (3825 3175);
DISPLAY INVISIBLE (3825 3175);
FORCEADD OFFPAGE..2
(3650 3050);
FORCEPROP 2 LAST $XR1 90 
J 0
(3929 3050);
DISPLAY 0.638298 (3929 3050);
PAINT MONO (3929 3050);
FORCEPROP 2 LAST $XR0 24 
J 0
(3839 3050);
DISPLAY 0.638298 (3839 3050);
PAINT MONO (3839 3050);
FORCEPROP 2 LAST CDS_LIB standard
J 0
(3650 3050);
PAINT MONO (3650 3050);
DISPLAY INVISIBLE (3650 3050);
FORCEPROP 1 LAST OFFPAGE TRUE
J 0
(3975 2925);
DISPLAY 1.170213 (3975 2925);
PAINT GREEN (3975 2925);
DISPLAY INVISIBLE (3975 2925);
FORCEPROP 1 LAST COMMENT_BODY TRUE
J 0
(3605 2955);
DISPLAY 1.170213 (3605 2955);
PAINT GREEN (3605 2955);
DISPLAY INVISIBLE (3605 2955);
FORCEPROP 2 LAST PATH I169
J 0
(3825 3125);
DISPLAY 1.021277 (3825 3125);
DISPLAY INVISIBLE (3825 3125);
FORCEADD OFFPAGE..1
(-2800 2825);
FORCEPROP 2 LAST $XR0 24 
J 0
(-3021 2825);
DISPLAY 0.638298 (-3021 2825);
PAINT MONO (-3021 2825);
FORCEPROP 2 LAST CDS_LIB standard
J 0
(-2800 2825);
PAINT MONO (-2800 2825);
DISPLAY INVISIBLE (-2800 2825);
FORCEPROP 1 LAST OFFPAGE TRUE
J 0
(-2475 2700);
DISPLAY 0.872340 (-2475 2700);
DISPLAY INVISIBLE (-2475 2700);
FORCEPROP 1 LAST COMMENT_BODY TRUE
J 0
(-2675 2725);
DISPLAY 0.872340 (-2675 2725);
PAINT GREEN (-2675 2725);
DISPLAY INVISIBLE (-2675 2725);
FORCEPROP 2 LAST PATH I17
J 0
(-2750 2900);
DISPLAY 1.021277 (-2750 2900);
DISPLAY INVISIBLE (-2750 2900);
FORCEADD OFFPAGE..3
(600 4150);
FORCEPROP 2 LAST $XR1 90 
J 0
(904 4150);
DISPLAY 0.638298 (904 4150);
PAINT MONO (904 4150);
FORCEPROP 2 LAST $XR0 24 
J 0
(814 4150);
DISPLAY 0.638298 (814 4150);
PAINT MONO (814 4150);
FORCEPROP 2 LAST CDS_LIB standard
J 2
(600 4150);
DISPLAY INVISIBLE (600 4150);
FORCEPROP 1 LAST OFFPAGE TRUE
J 0
(925 4025);
DISPLAY 0.872340 (925 4025);
DISPLAY INVISIBLE (925 4025);
FORCEPROP 1 LAST COMMENT_BODY TRUE
J 0
(550 4050);
DISPLAY 0.872340 (550 4050);
PAINT GREEN (550 4050);
DISPLAY INVISIBLE (550 4050);
FORCEPROP 2 LAST PATH I170
J 0
(800 4225);
DISPLAY 1.021277 (800 4225);
DISPLAY INVISIBLE (800 4225);
FORCEADD TAP..1
(2525 4125);
FORCEPROP 3 LASTPIN (2475 4125) SIG_NAME M_E_CPU0_SA_DQS_DP<9>
J 0
(2485 4135);
DISPLAY 0.659574 (2485 4135);
PAINT MONO (2485 4135);
DISPLAY INVISIBLE (2485 4135);
FORCEPROP 1 LASTPIN (2475 4125) BN 9
J 0
(2463 4133);
DISPLAY 0.680851 (2463 4133);
PAINT GREEN (2463 4133);
FORCEPROP 2 LAST CDS_LIB standard
J 0
(2525 4125);
DISPLAY INVISIBLE (2525 4125);
FORCEPROP 1 LAST BODY_TYPE PLUMBING
J 0
(2525 4175);
DISPLAY 0.872340 (2525 4175);
PAINT GREEN (2525 4175);
DISPLAY INVISIBLE (2525 4175);
FORCEPROP 1 LAST HDL_TAP TRUE
J 0
(2850 4000);
DISPLAY 0.872340 (2850 4000);
DISPLAY INVISIBLE (2850 4000);
FORCEPROP 1 LAST PATH I171
J 0
(2523 4125);
DISPLAY 0.872340 (2523 4125);
PAINT GREEN (2523 4125);
DISPLAY INVISIBLE (2523 4125);
FORCEADD TAP..1
(2525 4025);
FORCEPROP 3 LASTPIN (2475 4025) SIG_NAME M_E_CPU0_SA_DQS_DP<8>
J 0
(2485 4035);
DISPLAY 0.659574 (2485 4035);
PAINT MONO (2485 4035);
DISPLAY INVISIBLE (2485 4035);
FORCEPROP 1 LASTPIN (2475 4025) BN 8
J 0
(2463 4033);
DISPLAY 0.680851 (2463 4033);
PAINT GREEN (2463 4033);
FORCEPROP 2 LAST CDS_LIB standard
J 0
(2525 4025);
DISPLAY INVISIBLE (2525 4025);
FORCEPROP 1 LAST BODY_TYPE PLUMBING
J 0
(2525 4075);
DISPLAY 0.872340 (2525 4075);
PAINT GREEN (2525 4075);
DISPLAY INVISIBLE (2525 4075);
FORCEPROP 1 LAST HDL_TAP TRUE
J 0
(2850 3900);
DISPLAY 0.872340 (2850 3900);
DISPLAY INVISIBLE (2850 3900);
FORCEPROP 1 LAST PATH I172
J 0
(2523 4025);
DISPLAY 0.872340 (2523 4025);
PAINT GREEN (2523 4025);
DISPLAY INVISIBLE (2523 4025);
FORCEADD TAP..1
(2700 4075);
FORCEPROP 3 LASTPIN (2650 4075) SIG_NAME M_E_CPU0_SA_DQS_DN<9>
J 0
(2660 4085);
DISPLAY 0.659574 (2660 4085);
PAINT MONO (2660 4085);
DISPLAY INVISIBLE (2660 4085);
FORCEPROP 1 LASTPIN (2650 4075) BN 9
J 0
(2638 4083);
DISPLAY 0.680851 (2638 4083);
PAINT GREEN (2638 4083);
FORCEPROP 2 LAST CDS_LIB standard
J 0
(2700 4075);
DISPLAY INVISIBLE (2700 4075);
FORCEPROP 1 LAST BODY_TYPE PLUMBING
J 0
(2700 4125);
DISPLAY 0.872340 (2700 4125);
PAINT GREEN (2700 4125);
DISPLAY INVISIBLE (2700 4125);
FORCEPROP 1 LAST HDL_TAP TRUE
J 0
(3025 3950);
DISPLAY 0.872340 (3025 3950);
DISPLAY INVISIBLE (3025 3950);
FORCEPROP 1 LAST PATH I173
J 0
(2698 4075);
DISPLAY 0.872340 (2698 4075);
PAINT GREEN (2698 4075);
DISPLAY INVISIBLE (2698 4075);
FORCEADD OFFPAGE..2
(3650 4100);
FORCEPROP 2 LAST $XR1 90 
J 0
(3929 4100);
DISPLAY 0.638298 (3929 4100);
PAINT MONO (3929 4100);
FORCEPROP 2 LAST $XR0 24 
J 0
(3839 4100);
DISPLAY 0.638298 (3839 4100);
PAINT MONO (3839 4100);
FORCEPROP 2 LAST CDS_LIB standard
J 0
(3650 4100);
PAINT MONO (3650 4100);
DISPLAY INVISIBLE (3650 4100);
FORCEPROP 1 LAST OFFPAGE TRUE
J 0
(3975 3975);
DISPLAY 1.170213 (3975 3975);
PAINT GREEN (3975 3975);
DISPLAY INVISIBLE (3975 3975);
FORCEPROP 1 LAST COMMENT_BODY TRUE
J 0
(3605 4005);
DISPLAY 1.170213 (3605 4005);
PAINT GREEN (3605 4005);
DISPLAY INVISIBLE (3605 4005);
FORCEPROP 2 LAST PATH I174
J 0
(3825 4175);
DISPLAY 1.021277 (3825 4175);
DISPLAY INVISIBLE (3825 4175);
FORCEADD OFFPAGE..2
(3650 4150);
FORCEPROP 2 LAST $XR1 90 
J 0
(3929 4150);
DISPLAY 0.638298 (3929 4150);
PAINT MONO (3929 4150);
FORCEPROP 2 LAST $XR0 24 
J 0
(3839 4150);
DISPLAY 0.638298 (3839 4150);
PAINT MONO (3839 4150);
FORCEPROP 2 LAST CDS_LIB standard
J 0
(3650 4150);
PAINT MONO (3650 4150);
DISPLAY INVISIBLE (3650 4150);
FORCEPROP 1 LAST OFFPAGE TRUE
J 0
(3975 4025);
DISPLAY 1.170213 (3975 4025);
PAINT GREEN (3975 4025);
DISPLAY INVISIBLE (3975 4025);
FORCEPROP 1 LAST COMMENT_BODY TRUE
J 0
(3605 4055);
DISPLAY 1.170213 (3605 4055);
PAINT GREEN (3605 4055);
DISPLAY INVISIBLE (3605 4055);
FORCEPROP 2 LAST PATH I175
J 0
(3825 4225);
DISPLAY 1.021277 (3825 4225);
DISPLAY INVISIBLE (3825 4225);
FORCEADD VCC_CORE..1
(4200 4675);
FORCEPROP 3 LASTPIN (4200 4625) SIG_NAME P12V_S3_AUX_CPU0_NVDIMM\g
J 0
(4210 4635);
DISPLAY 0.659574 (4210 4635);
PAINT MONO (4210 4635);
DISPLAY INVISIBLE (4210 4635);
FORCEPROP 1 LAST HDL_POWER P12V_S3_AUX_CPU0_NVDIMM
J 1
(4200 4725);
DISPLAY 1.148936 (4200 4725);
PAINT GREEN (4200 4725);
FORCEPROP 2 LAST CDS_LIB logical_power
J 0
(4200 4675);
PAINT MONO (4200 4675);
DISPLAY INVISIBLE (4200 4675);
FORCEPROP 1 LAST PATH I176
J 0
(4250 4700);
DISPLAY 0.872340 (4250 4700);
PAINT AQUA (4250 4700);
DISPLAY INVISIBLE (4250 4700);
FORCEADD UNIVERSAL_GND..1
(5900 425);
FORCEPROP 3 LASTPIN (5900 475) SIG_NAME GND\g
J 0
(5910 485);
DISPLAY 0.659574 (5910 485);
PAINT MONO (5910 485);
DISPLAY INVISIBLE (5910 485);
FORCEPROP 2 LAST CDS_LIB logical_power
J 0
(5900 425);
PAINT MONO (5900 425);
DISPLAY INVISIBLE (5900 425);
FORCEPROP 1 LAST HDL_POWER GND
J 1
(5925 350);
DISPLAY 0.872340 (5925 350);
PAINT GREEN (5925 350);
DISPLAY INVISIBLE (5925 350);
FORCEPROP 1 LAST PATH I177
J 0
(5975 425);
DISPLAY 0.872340 (5975 425);
PAINT AQUA (5975 425);
DISPLAY INVISIBLE (5975 425);
FORCEADD SCONN288_ADR50017P087CC..2
(1625 3125);
FORCEPROP 1 LAST PART_NUMBER DFHST8FS460
J 0
(1020 4413);
DISPLAY 0.723404 (1020 4413);
PAINT GREEN (1020 4413);
DISPLAY INVISIBLE (1020 4413);
FORCEPROP 1 LAST MATERIAL IO
J 0
(1020 4286);
DISPLAY 0.723404 (1020 4286);
PAINT GREEN (1020 4286);
FORCEPROP 2 LAST PART_TYPE SMLF
J 0
(1025 4650);
DISPLAY 1.021277 (1025 4650);
FORCEPROP 2 LAST VALUE SCONN288_ADR50017-P087CC
J 0
(1025 4600);
DISPLAY 1.021277 (1025 4600);
FORCEPROP 1 LAST LOCATION J10
J 0
(1020 4560);
DISPLAY 0.723404 (1020 4560);
PAINT GREEN (1020 4560);
FORCEPROP 0 LASTPIN (2375 3175) $PN 12
J 0
(2385 3185);
DISPLAY 0.680851 (2385 3185);
PAINT MONO (2385 3185);
FORCEPROP 0 LASTPIN (2375 3225) $PN 11
J 0
(2385 3235);
DISPLAY 0.680851 (2385 3235);
PAINT MONO (2385 3235);
FORCEPROP 0 LASTPIN (2375 2125) $PN 105
J 0
(2385 2135);
DISPLAY 0.680851 (2385 2135);
PAINT MONO (2385 2135);
FORCEPROP 0 LASTPIN (2375 2175) $PN 104
J 0
(2385 2185);
DISPLAY 0.680851 (2385 2185);
PAINT MONO (2385 2185);
FORCEPROP 0 LASTPIN (2375 3275) $PN 23
J 0
(2385 3285);
DISPLAY 0.680851 (2385 3285);
PAINT MONO (2385 3285);
FORCEPROP 0 LASTPIN (2375 3325) $PN 22
J 0
(2385 3335);
DISPLAY 0.680851 (2385 3335);
PAINT MONO (2385 3335);
FORCEPROP 0 LASTPIN (2375 2225) $PN 116
J 0
(2385 2235);
DISPLAY 0.680851 (2385 2235);
PAINT MONO (2385 2235);
FORCEPROP 0 LASTPIN (2375 2275) $PN 115
J 0
(2385 2285);
DISPLAY 0.680851 (2385 2285);
PAINT MONO (2385 2285);
FORCEPROP 0 LASTPIN (2375 3375) $PN 34
J 0
(2385 3385);
DISPLAY 0.680851 (2385 3385);
PAINT MONO (2385 3385);
FORCEPROP 0 LASTPIN (2375 3425) $PN 33
J 0
(2385 3435);
DISPLAY 0.680851 (2385 3435);
PAINT MONO (2385 3435);
FORCEPROP 0 LASTPIN (2375 2325) $PN 127
J 0
(2385 2335);
DISPLAY 0.680851 (2385 2335);
PAINT MONO (2385 2335);
FORCEPROP 0 LASTPIN (2375 2375) $PN 126
J 0
(2385 2385);
DISPLAY 0.680851 (2385 2385);
PAINT MONO (2385 2385);
FORCEPROP 0 LASTPIN (2375 3475) $PN 45
J 0
(2385 3485);
DISPLAY 0.680851 (2385 3485);
PAINT MONO (2385 3485);
FORCEPROP 0 LASTPIN (2375 3525) $PN 44
J 0
(2385 3535);
DISPLAY 0.680851 (2385 3535);
PAINT MONO (2385 3535);
FORCEPROP 0 LASTPIN (2375 2425) $PN 138
J 0
(2385 2435);
DISPLAY 0.680851 (2385 2435);
PAINT MONO (2385 2435);
FORCEPROP 0 LASTPIN (2375 2475) $PN 137
J 0
(2385 2485);
DISPLAY 0.680851 (2385 2485);
PAINT MONO (2385 2485);
FORCEPROP 0 LASTPIN (2375 3575) $PN 56
J 0
(2385 3585);
DISPLAY 0.680851 (2385 3585);
PAINT MONO (2385 3585);
FORCEPROP 0 LASTPIN (2375 3625) $PN 55
J 0
(2385 3635);
DISPLAY 0.680851 (2385 3635);
PAINT MONO (2385 3635);
FORCEPROP 0 LASTPIN (2375 2525) $PN 238
J 0
(2385 2535);
DISPLAY 0.680851 (2385 2535);
PAINT MONO (2385 2535);
FORCEPROP 0 LASTPIN (2375 2575) $PN 239
J 0
(2385 2585);
DISPLAY 0.680851 (2385 2585);
PAINT MONO (2385 2585);
FORCEPROP 0 LASTPIN (2375 3675) $PN 156
J 0
(2385 3685);
DISPLAY 0.680851 (2385 3685);
PAINT MONO (2385 3685);
FORCEPROP 0 LASTPIN (2375 3725) $PN 157
J 0
(2385 3735);
DISPLAY 0.680851 (2385 3735);
PAINT MONO (2385 3735);
FORCEPROP 0 LASTPIN (2375 2625) $PN 249
J 0
(2385 2635);
DISPLAY 0.680851 (2385 2635);
PAINT MONO (2385 2635);
FORCEPROP 0 LASTPIN (2375 2675) $PN 250
J 0
(2385 2685);
DISPLAY 0.680851 (2385 2685);
PAINT MONO (2385 2685);
FORCEPROP 0 LASTPIN (2375 3775) $PN 167
J 0
(2385 3785);
DISPLAY 0.680851 (2385 3785);
PAINT MONO (2385 3785);
FORCEPROP 0 LASTPIN (2375 3825) $PN 168
J 0
(2385 3835);
DISPLAY 0.680851 (2385 3835);
PAINT MONO (2385 3835);
FORCEPROP 0 LASTPIN (2375 2725) $PN 260
J 0
(2385 2735);
DISPLAY 0.680851 (2385 2735);
PAINT MONO (2385 2735);
FORCEPROP 0 LASTPIN (2375 2775) $PN 261
J 0
(2385 2785);
DISPLAY 0.680851 (2385 2785);
PAINT MONO (2385 2785);
FORCEPROP 0 LASTPIN (2375 3875) $PN 178
J 0
(2385 3885);
DISPLAY 0.680851 (2385 3885);
PAINT MONO (2385 3885);
FORCEPROP 0 LASTPIN (2375 3925) $PN 179
J 0
(2385 3935);
DISPLAY 0.680851 (2385 3935);
PAINT MONO (2385 3935);
FORCEPROP 0 LASTPIN (2375 2825) $PN 271
J 0
(2385 2835);
DISPLAY 0.680851 (2385 2835);
PAINT MONO (2385 2835);
FORCEPROP 0 LASTPIN (2375 2875) $PN 272
J 0
(2385 2885);
DISPLAY 0.680851 (2385 2885);
PAINT MONO (2385 2885);
FORCEPROP 0 LASTPIN (2375 3975) $PN 189
J 0
(2385 3985);
DISPLAY 0.680851 (2385 3985);
PAINT MONO (2385 3985);
FORCEPROP 0 LASTPIN (2375 4025) $PN 190
J 0
(2385 4035);
DISPLAY 0.680851 (2385 4035);
PAINT MONO (2385 4035);
FORCEPROP 0 LASTPIN (2375 2925) $PN 282
J 0
(2385 2935);
DISPLAY 0.680851 (2385 2935);
PAINT MONO (2385 2935);
FORCEPROP 0 LASTPIN (2375 2975) $PN 283
J 0
(2385 2985);
DISPLAY 0.680851 (2385 2985);
PAINT MONO (2385 2985);
FORCEPROP 0 LASTPIN (2375 4075) $PN 200
J 0
(2385 4085);
DISPLAY 0.680851 (2385 4085);
PAINT MONO (2385 4085);
FORCEPROP 0 LASTPIN (2375 4125) $PN 201
J 0
(2385 4135);
DISPLAY 0.680851 (2385 4135);
PAINT MONO (2385 4135);
FORCEPROP 0 LASTPIN (2375 3025) $PN 94
J 0
(2385 3035);
DISPLAY 0.680851 (2385 3035);
PAINT MONO (2385 3035);
FORCEPROP 0 LASTPIN (2375 3075) $PN 93
J 0
(2385 3085);
DISPLAY 0.680851 (2385 3085);
PAINT MONO (2385 3085);
FORCEPROP 1 LAST NEEDS_NO_SIZE TRUE
J 0
(1625 3125);
DISPLAY 0.723404 (1625 3125);
PAINT GREEN (1625 3125);
DISPLAY INVISIBLE (1625 3125);
FORCEPROP 1 LAST CDS_LMAN_SYM_OUTLINE -600,1150,600,-1150
J 0
(1625 3125);
DISPLAY 0.468085 (1625 3125);
PAINT GREEN (1625 3125);
DISPLAY INVISIBLE (1625 3125);
FORCEPROP 2 LAST CDS_LIB pure_quanta
J 0
(1625 3125);
DISPLAY INVISIBLE (1625 3125);
FORCEPROP 0 LAST $SEC 2
J 0
(1025 4700);
DISPLAY 0.680851 (1025 4700);
PAINT MONO (1025 4700);
DISPLAY INVISIBLE (1025 4700);
FORCEPROP 0 LAST CDS_SEC 2
J 0
(1025 4700);
DISPLAY 1.021277 (1025 4700);
DISPLAY INVISIBLE (1025 4700);
FORCEPROP 1 LAST PATH I178
J 0
(1625 3125);
DISPLAY 0.723404 (1625 3125);
PAINT GREEN (1625 3125);
DISPLAY INVISIBLE (1625 3125);
FORCEADD Q_RES..1
(-2825 1400);
FORCEPROP 1 LAST PART_NUMBER CS04992FB07
J 0
(-2725 1375);
DISPLAY 0.404255 (-2725 1375);
DISPLAY INVISIBLE (-2725 1375);
FORCEPROP 1 LAST VALUE 49.9
J 2
(-2600 1400);
DISPLAY 0.510638 (-2600 1400);
FORCEPROP 1 LAST MATERIAL CHIP
J 0
(-2975 1350);
DISPLAY 0.404255 (-2975 1350);
FORCEPROP 1 LAST $LOCATION R3884
J 0
(-3050 1400);
DISPLAY 0.638298 (-3050 1400);
FORCEPROP 1 LASTPIN (-2925 1400) $PN 1
J 0
(-2913 1412);
DISPLAY 0.787234 (-2913 1412);
PAINT MONO (-2913 1412);
FORCEPROP 1 LASTPIN (-2725 1400) $PN 2
J 0
(-2763 1412);
DISPLAY 0.787234 (-2763 1412);
PAINT MONO (-2763 1412);
FORCEPROP 2 LAST CDS_LIB pure_quanta
J 0
(-2825 1400);
DISPLAY INVISIBLE (-2825 1400);
FORCEPROP 1 LAST PACK_TYPE 0402LF
J 0
(-2525 1400);
DISPLAY 0.510638 (-2525 1400);
DISPLAY INVISIBLE (-2525 1400);
FORCEPROP 1 LAST WATTAGE 1/16W
J 2
(-2525 1350);
DISPLAY 0.404255 (-2525 1350);
DISPLAY INVISIBLE (-2525 1350);
FORCEPROP 1 LAST TOLERANCE 1%
J 0
(-2600 1400);
DISPLAY 0.510638 (-2600 1400);
DISPLAY INVISIBLE (-2600 1400);
FORCEPROP 0 LAST CDS_LOCATION R3884
J 0
(-2975 1450);
DISPLAY 1.021277 (-2975 1450);
DISPLAY INVISIBLE (-2975 1450);
FORCEPROP 0 LAST $SEC 1
J 0
(-2975 1450);
DISPLAY 0.680851 (-2975 1450);
PAINT MONO (-2975 1450);
DISPLAY INVISIBLE (-2975 1450);
FORCEPROP 0 LAST CDS_SEC 1
J 0
(-2975 1450);
DISPLAY 1.021277 (-2975 1450);
DISPLAY INVISIBLE (-2975 1450);
FORCEPROP 1 LAST PATH I179
J 0
(-2875 1550);
DISPLAY 0.978723 (-2875 1550);
PAINT WHITE (-2875 1550);
DISPLAY INVISIBLE (-2875 1550);
FORCEADD OFFPAGE..1
(-2800 2875);
FORCEPROP 2 LAST $XR0 24 
J 0
(-3021 2875);
DISPLAY 0.638298 (-3021 2875);
PAINT MONO (-3021 2875);
FORCEPROP 2 LAST CDS_LIB standard
J 0
(-2800 2875);
PAINT MONO (-2800 2875);
DISPLAY INVISIBLE (-2800 2875);
FORCEPROP 1 LAST OFFPAGE TRUE
J 0
(-2475 2750);
DISPLAY 0.872340 (-2475 2750);
DISPLAY INVISIBLE (-2475 2750);
FORCEPROP 1 LAST COMMENT_BODY TRUE
J 0
(-2675 2775);
DISPLAY 0.872340 (-2675 2775);
PAINT GREEN (-2675 2775);
DISPLAY INVISIBLE (-2675 2775);
FORCEPROP 2 LAST PATH I18
J 0
(-2750 2950);
DISPLAY 1.021277 (-2750 2950);
DISPLAY INVISIBLE (-2750 2950);
FORCEADD OFFPAGE..1
(-1625 1350);
FORCEPROP 2 LAST $XR7 97 
J 0
(-2507 1350);
DISPLAY 0.638298 (-2507 1350);
PAINT MONO (-2507 1350);
FORCEPROP 2 LAST $XR6 96 
J 0
(-2417 1350);
DISPLAY 0.638298 (-2417 1350);
PAINT MONO (-2417 1350);
FORCEPROP 2 LAST $XR5 95 
J 0
(-2327 1350);
DISPLAY 0.638298 (-2327 1350);
PAINT MONO (-2327 1350);
FORCEPROP 2 LAST $XR4 94 
J 0
(-2237 1350);
DISPLAY 0.638298 (-2237 1350);
PAINT MONO (-2237 1350);
FORCEPROP 2 LAST $XR3 93 
J 0
(-2147 1350);
DISPLAY 0.638298 (-2147 1350);
PAINT MONO (-2147 1350);
FORCEPROP 2 LAST $XR2 92 
J 0
(-2057 1350);
DISPLAY 0.638298 (-2057 1350);
PAINT MONO (-2057 1350);
FORCEPROP 2 LAST $XR1 90 
J 0
(-1967 1350);
DISPLAY 0.638298 (-1967 1350);
PAINT MONO (-1967 1350);
FORCEPROP 2 LAST $XR0 229 
J 0
(-1877 1350);
DISPLAY 0.638298 (-1877 1350);
PAINT MONO (-1877 1350);
FORCEPROP 2 LAST CDS_LIB standard
J 2
(-1625 1350);
DISPLAY INVISIBLE (-1625 1350);
FORCEPROP 1 LAST OFFPAGE TRUE
J 0
(-1300 1225);
DISPLAY 0.872340 (-1300 1225);
DISPLAY INVISIBLE (-1300 1225);
FORCEPROP 1 LAST COMMENT_BODY TRUE
J 0
(-1500 1250);
DISPLAY 0.872340 (-1500 1250);
PAINT GREEN (-1500 1250);
DISPLAY INVISIBLE (-1500 1250);
FORCEPROP 2 LAST PATH I180
J 2
(-1800 1425);
DISPLAY 1.021277 (-1800 1425);
DISPLAY INVISIBLE (-1800 1425);
FORCEADD OFFPAGE..1
(-2800 3025);
FORCEPROP 2 LAST $XR0 24 
J 0
(-3021 3025);
DISPLAY 0.638298 (-3021 3025);
PAINT MONO (-3021 3025);
FORCEPROP 2 LAST CDS_LIB standard
J 0
(-2800 3025);
PAINT MONO (-2800 3025);
DISPLAY INVISIBLE (-2800 3025);
FORCEPROP 1 LAST OFFPAGE TRUE
J 0
(-2475 2900);
DISPLAY 0.872340 (-2475 2900);
DISPLAY INVISIBLE (-2475 2900);
FORCEPROP 1 LAST COMMENT_BODY TRUE
J 0
(-2675 2925);
DISPLAY 0.872340 (-2675 2925);
PAINT GREEN (-2675 2925);
DISPLAY INVISIBLE (-2675 2925);
FORCEPROP 2 LAST PATH I19
J 0
(-2750 3100);
DISPLAY 1.021277 (-2750 3100);
DISPLAY INVISIBLE (-2750 3100);
FORCEADD Q_RES..2
(-1650 -25);
FORCEPROP 1 LAST PART_NUMBER CS31542FB02
J 0
(-1610 -150);
DISPLAY 0.978723 (-1610 -150);
DISPLAY INVISIBLE (-1610 -150);
FORCEPROP 1 LAST WATTAGE 1/16W
J 0
(-1610 -50);
DISPLAY 0.978723 (-1610 -50);
FORCEPROP 1 LAST MATERIAL CHIP
J 0
(-1610 -100);
DISPLAY 0.978723 (-1610 -100);
FORCEPROP 1 LAST TOLERANCE 1%
J 0
(-1605 0);
DISPLAY 0.978723 (-1605 0);
FORCEPROP 1 LAST VALUE 15.4K
J 0
(-1605 50);
DISPLAY 0.978723 (-1605 50);
FORCEPROP 1 LAST PACK_TYPE 0402LF
J 0
(-1610 -200);
DISPLAY 0.978723 (-1610 -200);
FORCEPROP 1 LAST $LOCATION R35
J 0
(-1605 100);
DISPLAY 0.978723 (-1605 100);
FORCEPROP 1 LASTPIN (-1650 75) $PN 1
J 0
(-1645 37);
DISPLAY 0.787234 (-1645 37);
PAINT MONO (-1645 37);
FORCEPROP 1 LASTPIN (-1650 -125) $PN 2
J 0
(-1645 -115);
DISPLAY 0.787234 (-1645 -115);
PAINT MONO (-1645 -115);
FORCEPROP 2 LAST CDS_LIB pure_quanta
J 0
(-1650 -25);
DISPLAY INVISIBLE (-1650 -25);
FORCEPROP 2 LAST CDS_LOCATION R35
J 0
(-1600 200);
DISPLAY 1.021277 (-1600 200);
DISPLAY INVISIBLE (-1600 200);
FORCEPROP 0 LAST $SEC 1
J 0
(-1600 150);
DISPLAY 0.680851 (-1600 150);
PAINT MONO (-1600 150);
DISPLAY INVISIBLE (-1600 150);
FORCEPROP 2 LAST CDS_SEC 1
J 0
(-1600 200);
DISPLAY 1.021277 (-1600 200);
DISPLAY INVISIBLE (-1600 200);
FORCEPROP 1 LAST PATH I2
J 0
(-1600 150);
DISPLAY 0.978723 (-1600 150);
PAINT WHITE (-1600 150);
DISPLAY INVISIBLE (-1600 150);
FORCEADD OFFPAGE..1
(-2800 2975);
FORCEPROP 2 LAST $XR0 24 
J 0
(-3021 2975);
DISPLAY 0.638298 (-3021 2975);
PAINT MONO (-3021 2975);
FORCEPROP 2 LAST CDS_LIB standard
J 0
(-2800 2975);
PAINT MONO (-2800 2975);
DISPLAY INVISIBLE (-2800 2975);
FORCEPROP 1 LAST OFFPAGE TRUE
J 0
(-2475 2850);
DISPLAY 0.872340 (-2475 2850);
DISPLAY INVISIBLE (-2475 2850);
FORCEPROP 1 LAST COMMENT_BODY TRUE
J 0
(-2675 2875);
DISPLAY 0.872340 (-2675 2875);
PAINT GREEN (-2675 2875);
DISPLAY INVISIBLE (-2675 2875);
FORCEPROP 2 LAST PATH I20
J 0
(-2750 3050);
DISPLAY 1.021277 (-2750 3050);
DISPLAY INVISIBLE (-2750 3050);
FORCEADD OFFPAGE..1
(-2800 3175);
FORCEPROP 2 LAST $XR0 24 
J 0
(-3021 3175);
DISPLAY 0.638298 (-3021 3175);
PAINT MONO (-3021 3175);
FORCEPROP 2 LAST CDS_LIB standard
J 0
(-2800 3175);
PAINT MONO (-2800 3175);
DISPLAY INVISIBLE (-2800 3175);
FORCEPROP 1 LAST OFFPAGE TRUE
J 0
(-2475 3050);
DISPLAY 0.872340 (-2475 3050);
DISPLAY INVISIBLE (-2475 3050);
FORCEPROP 1 LAST COMMENT_BODY TRUE
J 0
(-2675 3075);
DISPLAY 0.872340 (-2675 3075);
PAINT GREEN (-2675 3075);
DISPLAY INVISIBLE (-2675 3075);
FORCEPROP 2 LAST PATH I21
J 0
(-2750 3250);
DISPLAY 1.021277 (-2750 3250);
DISPLAY INVISIBLE (-2750 3250);
FORCEADD OFFPAGE..1
(-2800 3125);
FORCEPROP 2 LAST $XR0 24 
J 0
(-3021 3125);
DISPLAY 0.638298 (-3021 3125);
PAINT MONO (-3021 3125);
FORCEPROP 2 LAST CDS_LIB standard
J 0
(-2800 3125);
PAINT MONO (-2800 3125);
DISPLAY INVISIBLE (-2800 3125);
FORCEPROP 1 LAST OFFPAGE TRUE
J 0
(-2475 3000);
DISPLAY 0.872340 (-2475 3000);
DISPLAY INVISIBLE (-2475 3000);
FORCEPROP 1 LAST COMMENT_BODY TRUE
J 0
(-2675 3025);
DISPLAY 0.872340 (-2675 3025);
PAINT GREEN (-2675 3025);
DISPLAY INVISIBLE (-2675 3025);
FORCEPROP 2 LAST PATH I22
J 0
(-2750 3200);
DISPLAY 1.021277 (-2750 3200);
DISPLAY INVISIBLE (-2750 3200);
FORCEADD OFFPAGE..1
(-2800 3275);
FORCEPROP 2 LAST $XR1 90 
J 0
(-3111 3275);
DISPLAY 0.638298 (-3111 3275);
PAINT MONO (-3111 3275);
FORCEPROP 2 LAST $XR0 24 
J 0
(-3021 3275);
DISPLAY 0.638298 (-3021 3275);
PAINT MONO (-3021 3275);
FORCEPROP 2 LAST CDS_LIB standard
J 0
(-2800 3275);
PAINT MONO (-2800 3275);
DISPLAY INVISIBLE (-2800 3275);
FORCEPROP 1 LAST OFFPAGE TRUE
J 0
(-2475 3150);
DISPLAY 0.872340 (-2475 3150);
DISPLAY INVISIBLE (-2475 3150);
FORCEPROP 1 LAST COMMENT_BODY TRUE
J 0
(-2675 3175);
DISPLAY 0.872340 (-2675 3175);
PAINT GREEN (-2675 3175);
DISPLAY INVISIBLE (-2675 3175);
FORCEPROP 2 LAST PATH I23
J 0
(-2750 3350);
DISPLAY 1.021277 (-2750 3350);
DISPLAY INVISIBLE (-2750 3350);
FORCEADD OFFPAGE..1
(-2800 3325);
FORCEPROP 2 LAST $XR1 90 
J 0
(-3111 3325);
DISPLAY 0.638298 (-3111 3325);
PAINT MONO (-3111 3325);
FORCEPROP 2 LAST $XR0 24 
J 0
(-3021 3325);
DISPLAY 0.638298 (-3021 3325);
PAINT MONO (-3021 3325);
FORCEPROP 2 LAST CDS_LIB standard
J 0
(-2800 3325);
PAINT MONO (-2800 3325);
DISPLAY INVISIBLE (-2800 3325);
FORCEPROP 1 LAST OFFPAGE TRUE
J 0
(-2475 3200);
DISPLAY 0.872340 (-2475 3200);
DISPLAY INVISIBLE (-2475 3200);
FORCEPROP 1 LAST COMMENT_BODY TRUE
J 0
(-2675 3225);
DISPLAY 0.872340 (-2675 3225);
PAINT GREEN (-2675 3225);
DISPLAY INVISIBLE (-2675 3225);
FORCEPROP 2 LAST PATH I24
J 0
(-2750 3400);
DISPLAY 1.021277 (-2750 3400);
DISPLAY INVISIBLE (-2750 3400);
FORCEADD OFFPAGE..1
(-2800 3750);
FORCEPROP 2 LAST $XR1 90 
J 0
(-3111 3750);
DISPLAY 0.638298 (-3111 3750);
PAINT MONO (-3111 3750);
FORCEPROP 2 LAST $XR0 24 
J 0
(-3021 3750);
DISPLAY 0.638298 (-3021 3750);
PAINT MONO (-3021 3750);
FORCEPROP 2 LAST CDS_LIB standard
J 0
(-2800 3750);
PAINT MONO (-2800 3750);
DISPLAY INVISIBLE (-2800 3750);
FORCEPROP 1 LAST OFFPAGE TRUE
J 0
(-2475 3625);
DISPLAY 0.872340 (-2475 3625);
DISPLAY INVISIBLE (-2475 3625);
FORCEPROP 1 LAST COMMENT_BODY TRUE
J 0
(-2675 3650);
DISPLAY 0.872340 (-2675 3650);
PAINT GREEN (-2675 3650);
DISPLAY INVISIBLE (-2675 3650);
FORCEPROP 2 LAST PATH I25
J 0
(-2750 3825);
DISPLAY 1.021277 (-2750 3825);
DISPLAY INVISIBLE (-2750 3825);
FORCEADD TAP..1
R 2
(-1875 1975);
FORCEPROP 3 LASTPIN (-1825 1975) SIG_NAME M_E_CPU0_SB_CB<1>
J 0
(-1815 1985);
DISPLAY 0.659574 (-1815 1985);
PAINT MONO (-1815 1985);
DISPLAY INVISIBLE (-1815 1985);
FORCEPROP 1 LASTPIN (-1825 1975) BN 1
J 2
(-1813 1983);
DISPLAY 0.680851 (-1813 1983);
PAINT GREEN (-1813 1983);
FORCEPROP 2 LAST CDS_LIB standard
J 0
(-1875 1975);
DISPLAY INVISIBLE (-1875 1975);
FORCEPROP 1 LAST BODY_TYPE PLUMBING
J 2
(-1875 2025);
DISPLAY 0.872340 (-1875 2025);
PAINT GREEN (-1875 2025);
DISPLAY INVISIBLE (-1875 2025);
FORCEPROP 1 LAST HDL_TAP TRUE
J 2
(-2200 1850);
DISPLAY 0.872340 (-2200 1850);
DISPLAY INVISIBLE (-2200 1850);
FORCEPROP 1 LAST PATH I26
J 2
(-1873 1975);
DISPLAY 0.872340 (-1873 1975);
PAINT GREEN (-1873 1975);
DISPLAY INVISIBLE (-1873 1975);
FORCEADD TAP..1
R 2
(-1875 2025);
FORCEPROP 3 LASTPIN (-1825 2025) SIG_NAME M_E_CPU0_SB_CB<2>
J 0
(-1815 2035);
DISPLAY 0.659574 (-1815 2035);
PAINT MONO (-1815 2035);
DISPLAY INVISIBLE (-1815 2035);
FORCEPROP 1 LASTPIN (-1825 2025) BN 2
J 2
(-1813 2033);
DISPLAY 0.680851 (-1813 2033);
PAINT GREEN (-1813 2033);
FORCEPROP 2 LAST CDS_LIB standard
J 0
(-1875 2025);
DISPLAY INVISIBLE (-1875 2025);
FORCEPROP 1 LAST BODY_TYPE PLUMBING
J 2
(-1875 2075);
DISPLAY 0.872340 (-1875 2075);
PAINT GREEN (-1875 2075);
DISPLAY INVISIBLE (-1875 2075);
FORCEPROP 1 LAST HDL_TAP TRUE
J 2
(-2200 1900);
DISPLAY 0.872340 (-2200 1900);
DISPLAY INVISIBLE (-2200 1900);
FORCEPROP 1 LAST PATH I27
J 2
(-1873 2025);
DISPLAY 0.872340 (-1873 2025);
PAINT GREEN (-1873 2025);
DISPLAY INVISIBLE (-1873 2025);
FORCEADD TAP..1
R 2
(-1875 2075);
FORCEPROP 3 LASTPIN (-1825 2075) SIG_NAME M_E_CPU0_SB_CB<3>
J 0
(-1815 2085);
DISPLAY 0.659574 (-1815 2085);
PAINT MONO (-1815 2085);
DISPLAY INVISIBLE (-1815 2085);
FORCEPROP 1 LASTPIN (-1825 2075) BN 3
J 2
(-1813 2083);
DISPLAY 0.680851 (-1813 2083);
PAINT GREEN (-1813 2083);
FORCEPROP 2 LAST CDS_LIB standard
J 0
(-1875 2075);
DISPLAY INVISIBLE (-1875 2075);
FORCEPROP 1 LAST BODY_TYPE PLUMBING
J 2
(-1875 2125);
DISPLAY 0.872340 (-1875 2125);
PAINT GREEN (-1875 2125);
DISPLAY INVISIBLE (-1875 2125);
FORCEPROP 1 LAST HDL_TAP TRUE
J 2
(-2200 1950);
DISPLAY 0.872340 (-2200 1950);
DISPLAY INVISIBLE (-2200 1950);
FORCEPROP 1 LAST PATH I28
J 2
(-1873 2075);
DISPLAY 0.872340 (-1873 2075);
PAINT GREEN (-1873 2075);
DISPLAY INVISIBLE (-1873 2075);
FORCEADD TAP..1
R 2
(-1875 2125);
FORCEPROP 3 LASTPIN (-1825 2125) SIG_NAME M_E_CPU0_SB_CB<4>
J 0
(-1815 2135);
DISPLAY 0.659574 (-1815 2135);
PAINT MONO (-1815 2135);
DISPLAY INVISIBLE (-1815 2135);
FORCEPROP 1 LASTPIN (-1825 2125) BN 4
J 2
(-1813 2133);
DISPLAY 0.680851 (-1813 2133);
PAINT GREEN (-1813 2133);
FORCEPROP 2 LAST CDS_LIB standard
J 0
(-1875 2125);
DISPLAY INVISIBLE (-1875 2125);
FORCEPROP 1 LAST BODY_TYPE PLUMBING
J 2
(-1875 2175);
DISPLAY 0.872340 (-1875 2175);
PAINT GREEN (-1875 2175);
DISPLAY INVISIBLE (-1875 2175);
FORCEPROP 1 LAST HDL_TAP TRUE
J 2
(-2200 2000);
DISPLAY 0.872340 (-2200 2000);
DISPLAY INVISIBLE (-2200 2000);
FORCEPROP 1 LAST PATH I29
J 2
(-1873 2125);
DISPLAY 0.872340 (-1873 2125);
PAINT GREEN (-1873 2125);
DISPLAY INVISIBLE (-1873 2125);
FORCEADD OFFPAGE..2
R 2
(-2800 175);
FORCEPROP 2 LAST $XR0 91 
J 0
(-3024 175);
DISPLAY 0.638298 (-3024 175);
PAINT MONO (-3024 175);
FORCEPROP 2 LAST CDS_LIB standard
J 0
(-2800 175);
PAINT MONO (-2800 175);
DISPLAY INVISIBLE (-2800 175);
FORCEPROP 1 LAST OFFPAGE TRUE
J 2
(-3125 50);
DISPLAY 0.872340 (-3125 50);
DISPLAY INVISIBLE (-3125 50);
FORCEPROP 1 LAST COMMENT_BODY TRUE
J 2
(-2755 80);
DISPLAY 0.872340 (-2755 80);
PAINT GREEN (-2755 80);
DISPLAY INVISIBLE (-2755 80);
FORCEPROP 2 LAST PATH I3
J 0
(-2750 250);
DISPLAY 1.021277 (-2750 250);
DISPLAY INVISIBLE (-2750 250);
FORCEADD TAP..1
R 2
(-1875 2175);
FORCEPROP 3 LASTPIN (-1825 2175) SIG_NAME M_E_CPU0_SB_CB<5>
J 0
(-1815 2185);
DISPLAY 0.659574 (-1815 2185);
PAINT MONO (-1815 2185);
DISPLAY INVISIBLE (-1815 2185);
FORCEPROP 1 LASTPIN (-1825 2175) BN 5
J 2
(-1813 2183);
DISPLAY 0.680851 (-1813 2183);
PAINT GREEN (-1813 2183);
FORCEPROP 2 LAST CDS_LIB standard
J 0
(-1875 2175);
DISPLAY INVISIBLE (-1875 2175);
FORCEPROP 1 LAST BODY_TYPE PLUMBING
J 2
(-1875 2225);
DISPLAY 0.872340 (-1875 2225);
PAINT GREEN (-1875 2225);
DISPLAY INVISIBLE (-1875 2225);
FORCEPROP 1 LAST HDL_TAP TRUE
J 2
(-2200 2050);
DISPLAY 0.872340 (-2200 2050);
DISPLAY INVISIBLE (-2200 2050);
FORCEPROP 1 LAST PATH I30
J 2
(-1873 2175);
DISPLAY 0.872340 (-1873 2175);
PAINT GREEN (-1873 2175);
DISPLAY INVISIBLE (-1873 2175);
FORCEADD TAP..1
R 2
(-1875 2225);
FORCEPROP 3 LASTPIN (-1825 2225) SIG_NAME M_E_CPU0_SB_CB<6>
J 0
(-1815 2235);
DISPLAY 0.659574 (-1815 2235);
PAINT MONO (-1815 2235);
DISPLAY INVISIBLE (-1815 2235);
FORCEPROP 1 LASTPIN (-1825 2225) BN 6
J 2
(-1813 2233);
DISPLAY 0.680851 (-1813 2233);
PAINT GREEN (-1813 2233);
FORCEPROP 2 LAST CDS_LIB standard
J 0
(-1875 2225);
DISPLAY INVISIBLE (-1875 2225);
FORCEPROP 1 LAST BODY_TYPE PLUMBING
J 2
(-1875 2275);
DISPLAY 0.872340 (-1875 2275);
PAINT GREEN (-1875 2275);
DISPLAY INVISIBLE (-1875 2275);
FORCEPROP 1 LAST HDL_TAP TRUE
J 2
(-2200 2100);
DISPLAY 0.872340 (-2200 2100);
DISPLAY INVISIBLE (-2200 2100);
FORCEPROP 1 LAST PATH I31
J 2
(-1873 2225);
DISPLAY 0.872340 (-1873 2225);
PAINT GREEN (-1873 2225);
DISPLAY INVISIBLE (-1873 2225);
FORCEADD TAP..1
R 2
(-1875 2275);
FORCEPROP 3 LASTPIN (-1825 2275) SIG_NAME M_E_CPU0_SB_CB<7>
J 0
(-1815 2285);
DISPLAY 0.659574 (-1815 2285);
PAINT MONO (-1815 2285);
DISPLAY INVISIBLE (-1815 2285);
FORCEPROP 1 LASTPIN (-1825 2275) BN 7
J 2
(-1813 2283);
DISPLAY 0.680851 (-1813 2283);
PAINT GREEN (-1813 2283);
FORCEPROP 2 LAST CDS_LIB standard
J 0
(-1875 2275);
DISPLAY INVISIBLE (-1875 2275);
FORCEPROP 1 LAST BODY_TYPE PLUMBING
J 2
(-1875 2325);
DISPLAY 0.872340 (-1875 2325);
PAINT GREEN (-1875 2325);
DISPLAY INVISIBLE (-1875 2325);
FORCEPROP 1 LAST HDL_TAP TRUE
J 2
(-2200 2150);
DISPLAY 0.872340 (-2200 2150);
DISPLAY INVISIBLE (-2200 2150);
FORCEPROP 1 LAST PATH I32
J 2
(-1873 2275);
DISPLAY 0.872340 (-1873 2275);
PAINT GREEN (-1873 2275);
DISPLAY INVISIBLE (-1873 2275);
FORCEADD TAP..1
R 2
(-1875 2425);
FORCEPROP 3 LASTPIN (-1825 2425) SIG_NAME M_E_CPU0_SA_CB<1>
J 0
(-1815 2435);
DISPLAY 0.659574 (-1815 2435);
PAINT MONO (-1815 2435);
DISPLAY INVISIBLE (-1815 2435);
FORCEPROP 1 LASTPIN (-1825 2425) BN 1
J 2
(-1813 2433);
DISPLAY 0.680851 (-1813 2433);
PAINT GREEN (-1813 2433);
FORCEPROP 2 LAST CDS_LIB standard
J 0
(-1875 2425);
DISPLAY INVISIBLE (-1875 2425);
FORCEPROP 1 LAST BODY_TYPE PLUMBING
J 2
(-1875 2475);
DISPLAY 0.872340 (-1875 2475);
PAINT GREEN (-1875 2475);
DISPLAY INVISIBLE (-1875 2475);
FORCEPROP 1 LAST HDL_TAP TRUE
J 2
(-2200 2300);
DISPLAY 0.872340 (-2200 2300);
DISPLAY INVISIBLE (-2200 2300);
FORCEPROP 1 LAST PATH I33
J 2
(-1873 2425);
DISPLAY 0.872340 (-1873 2425);
PAINT GREEN (-1873 2425);
DISPLAY INVISIBLE (-1873 2425);
FORCEADD TAP..1
R 2
(-1875 2375);
FORCEPROP 3 LASTPIN (-1825 2375) SIG_NAME M_E_CPU0_SA_CB<0>
J 0
(-1815 2385);
DISPLAY 0.659574 (-1815 2385);
PAINT MONO (-1815 2385);
DISPLAY INVISIBLE (-1815 2385);
FORCEPROP 1 LASTPIN (-1825 2375) BN 0
J 2
(-1813 2383);
DISPLAY 0.680851 (-1813 2383);
PAINT GREEN (-1813 2383);
FORCEPROP 2 LAST CDS_LIB standard
J 0
(-1875 2375);
PAINT MONO (-1875 2375);
DISPLAY INVISIBLE (-1875 2375);
FORCEPROP 1 LAST BODY_TYPE PLUMBING
J 2
(-1875 2425);
DISPLAY 0.872340 (-1875 2425);
PAINT GREEN (-1875 2425);
DISPLAY INVISIBLE (-1875 2425);
FORCEPROP 1 LAST HDL_TAP TRUE
J 2
(-2200 2250);
DISPLAY 0.872340 (-2200 2250);
DISPLAY INVISIBLE (-2200 2250);
FORCEPROP 1 LAST PATH I34
J 2
(-1873 2375);
DISPLAY 0.872340 (-1873 2375);
PAINT GREEN (-1873 2375);
DISPLAY INVISIBLE (-1873 2375);
FORCEADD TAP..1
R 2
(-1875 2475);
FORCEPROP 3 LASTPIN (-1825 2475) SIG_NAME M_E_CPU0_SA_CB<2>
J 0
(-1815 2485);
DISPLAY 0.659574 (-1815 2485);
PAINT MONO (-1815 2485);
DISPLAY INVISIBLE (-1815 2485);
FORCEPROP 1 LASTPIN (-1825 2475) BN 2
J 2
(-1813 2483);
DISPLAY 0.680851 (-1813 2483);
PAINT GREEN (-1813 2483);
FORCEPROP 2 LAST CDS_LIB standard
J 0
(-1875 2475);
DISPLAY INVISIBLE (-1875 2475);
FORCEPROP 1 LAST BODY_TYPE PLUMBING
J 2
(-1875 2525);
DISPLAY 0.872340 (-1875 2525);
PAINT GREEN (-1875 2525);
DISPLAY INVISIBLE (-1875 2525);
FORCEPROP 1 LAST HDL_TAP TRUE
J 2
(-2200 2350);
DISPLAY 0.872340 (-2200 2350);
DISPLAY INVISIBLE (-2200 2350);
FORCEPROP 1 LAST PATH I35
J 2
(-1873 2475);
DISPLAY 0.872340 (-1873 2475);
PAINT GREEN (-1873 2475);
DISPLAY INVISIBLE (-1873 2475);
FORCEADD TAP..1
R 2
(-1875 2525);
FORCEPROP 3 LASTPIN (-1825 2525) SIG_NAME M_E_CPU0_SA_CB<3>
J 0
(-1815 2535);
DISPLAY 0.659574 (-1815 2535);
PAINT MONO (-1815 2535);
DISPLAY INVISIBLE (-1815 2535);
FORCEPROP 1 LASTPIN (-1825 2525) BN 3
J 2
(-1813 2533);
DISPLAY 0.680851 (-1813 2533);
PAINT GREEN (-1813 2533);
FORCEPROP 2 LAST CDS_LIB standard
J 0
(-1875 2525);
DISPLAY INVISIBLE (-1875 2525);
FORCEPROP 1 LAST BODY_TYPE PLUMBING
J 2
(-1875 2575);
DISPLAY 0.872340 (-1875 2575);
PAINT GREEN (-1875 2575);
DISPLAY INVISIBLE (-1875 2575);
FORCEPROP 1 LAST HDL_TAP TRUE
J 2
(-2200 2400);
DISPLAY 0.872340 (-2200 2400);
DISPLAY INVISIBLE (-2200 2400);
FORCEPROP 1 LAST PATH I36
J 2
(-1873 2525);
DISPLAY 0.872340 (-1873 2525);
PAINT GREEN (-1873 2525);
DISPLAY INVISIBLE (-1873 2525);
FORCEADD TAP..1
R 2
(-1875 2575);
FORCEPROP 3 LASTPIN (-1825 2575) SIG_NAME M_E_CPU0_SA_CB<4>
J 0
(-1815 2585);
DISPLAY 0.659574 (-1815 2585);
PAINT MONO (-1815 2585);
DISPLAY INVISIBLE (-1815 2585);
FORCEPROP 1 LASTPIN (-1825 2575) BN 4
J 2
(-1813 2583);
DISPLAY 0.680851 (-1813 2583);
PAINT GREEN (-1813 2583);
FORCEPROP 2 LAST CDS_LIB standard
J 0
(-1875 2575);
DISPLAY INVISIBLE (-1875 2575);
FORCEPROP 1 LAST BODY_TYPE PLUMBING
J 2
(-1875 2625);
DISPLAY 0.872340 (-1875 2625);
PAINT GREEN (-1875 2625);
DISPLAY INVISIBLE (-1875 2625);
FORCEPROP 1 LAST HDL_TAP TRUE
J 2
(-2200 2450);
DISPLAY 0.872340 (-2200 2450);
DISPLAY INVISIBLE (-2200 2450);
FORCEPROP 1 LAST PATH I37
J 2
(-1873 2575);
DISPLAY 0.872340 (-1873 2575);
PAINT GREEN (-1873 2575);
DISPLAY INVISIBLE (-1873 2575);
FORCEADD TAP..1
R 2
(-1875 2675);
FORCEPROP 3 LASTPIN (-1825 2675) SIG_NAME M_E_CPU0_SA_CB<6>
J 0
(-1815 2685);
DISPLAY 0.659574 (-1815 2685);
PAINT MONO (-1815 2685);
DISPLAY INVISIBLE (-1815 2685);
FORCEPROP 1 LASTPIN (-1825 2675) BN 6
J 2
(-1813 2683);
DISPLAY 0.680851 (-1813 2683);
PAINT GREEN (-1813 2683);
FORCEPROP 2 LAST CDS_LIB standard
J 0
(-1875 2675);
DISPLAY INVISIBLE (-1875 2675);
FORCEPROP 1 LAST BODY_TYPE PLUMBING
J 2
(-1875 2725);
DISPLAY 0.872340 (-1875 2725);
PAINT GREEN (-1875 2725);
DISPLAY INVISIBLE (-1875 2725);
FORCEPROP 1 LAST HDL_TAP TRUE
J 2
(-2200 2550);
DISPLAY 0.872340 (-2200 2550);
DISPLAY INVISIBLE (-2200 2550);
FORCEPROP 1 LAST PATH I38
J 2
(-1873 2675);
DISPLAY 0.872340 (-1873 2675);
PAINT GREEN (-1873 2675);
DISPLAY INVISIBLE (-1873 2675);
FORCEADD TAP..1
R 2
(-1875 2625);
FORCEPROP 3 LASTPIN (-1825 2625) SIG_NAME M_E_CPU0_SA_CB<5>
J 0
(-1815 2635);
DISPLAY 0.659574 (-1815 2635);
PAINT MONO (-1815 2635);
DISPLAY INVISIBLE (-1815 2635);
FORCEPROP 1 LASTPIN (-1825 2625) BN 5
J 2
(-1813 2633);
DISPLAY 0.680851 (-1813 2633);
PAINT GREEN (-1813 2633);
FORCEPROP 2 LAST CDS_LIB standard
J 0
(-1875 2625);
DISPLAY INVISIBLE (-1875 2625);
FORCEPROP 1 LAST BODY_TYPE PLUMBING
J 2
(-1875 2675);
DISPLAY 0.872340 (-1875 2675);
PAINT GREEN (-1875 2675);
DISPLAY INVISIBLE (-1875 2675);
FORCEPROP 1 LAST HDL_TAP TRUE
J 2
(-2200 2500);
DISPLAY 0.872340 (-2200 2500);
DISPLAY INVISIBLE (-2200 2500);
FORCEPROP 1 LAST PATH I39
J 2
(-1873 2625);
DISPLAY 0.872340 (-1873 2625);
PAINT GREEN (-1873 2625);
DISPLAY INVISIBLE (-1873 2625);
FORCEADD OFFPAGE..2
R 2
(-2800 725);
FORCEPROP 2 LAST $XR0 24 
J 0
(-3024 725);
DISPLAY 0.638298 (-3024 725);
PAINT MONO (-3024 725);
FORCEPROP 2 LAST CDS_LIB standard
J 0
(-2800 725);
PAINT MONO (-2800 725);
DISPLAY INVISIBLE (-2800 725);
FORCEPROP 1 LAST OFFPAGE TRUE
J 2
(-3125 600);
DISPLAY 0.872340 (-3125 600);
DISPLAY INVISIBLE (-3125 600);
FORCEPROP 1 LAST COMMENT_BODY TRUE
J 2
(-2755 630);
DISPLAY 0.872340 (-2755 630);
PAINT GREEN (-2755 630);
DISPLAY INVISIBLE (-2755 630);
FORCEPROP 2 LAST PATH I4
J 0
(-2750 800);
DISPLAY 1.021277 (-2750 800);
DISPLAY INVISIBLE (-2750 800);
FORCEADD TAP..1
R 2
(-1875 2725);
FORCEPROP 3 LASTPIN (-1825 2725) SIG_NAME M_E_CPU0_SA_CB<7>
J 0
(-1815 2735);
DISPLAY 0.659574 (-1815 2735);
PAINT MONO (-1815 2735);
DISPLAY INVISIBLE (-1815 2735);
FORCEPROP 1 LASTPIN (-1825 2725) BN 7
J 2
(-1813 2733);
DISPLAY 0.680851 (-1813 2733);
PAINT GREEN (-1813 2733);
FORCEPROP 2 LAST CDS_LIB standard
J 0
(-1875 2725);
DISPLAY INVISIBLE (-1875 2725);
FORCEPROP 1 LAST BODY_TYPE PLUMBING
J 2
(-1875 2775);
DISPLAY 0.872340 (-1875 2775);
PAINT GREEN (-1875 2775);
DISPLAY INVISIBLE (-1875 2775);
FORCEPROP 1 LAST HDL_TAP TRUE
J 2
(-2200 2600);
DISPLAY 0.872340 (-2200 2600);
DISPLAY INVISIBLE (-2200 2600);
FORCEPROP 1 LAST PATH I40
J 2
(-1873 2725);
DISPLAY 0.872340 (-1873 2725);
PAINT GREEN (-1873 2725);
DISPLAY INVISIBLE (-1873 2725);
FORCEADD TAP..1
R 2
(-1875 3425);
FORCEPROP 3 LASTPIN (-1825 3425) SIG_NAME M_E_CPU0_SB_CA<0>
J 0
(-1815 3435);
DISPLAY 0.659574 (-1815 3435);
PAINT MONO (-1815 3435);
DISPLAY INVISIBLE (-1815 3435);
FORCEPROP 1 LASTPIN (-1825 3425) BN 0
J 2
(-1813 3433);
DISPLAY 0.680851 (-1813 3433);
PAINT GREEN (-1813 3433);
FORCEPROP 2 LAST CDS_LIB standard
J 0
(-1875 3425);
DISPLAY INVISIBLE (-1875 3425);
FORCEPROP 1 LAST BODY_TYPE PLUMBING
J 2
(-1875 3475);
DISPLAY 0.872340 (-1875 3475);
PAINT GREEN (-1875 3475);
DISPLAY INVISIBLE (-1875 3475);
FORCEPROP 1 LAST HDL_TAP TRUE
J 2
(-2200 3300);
DISPLAY 0.872340 (-2200 3300);
DISPLAY INVISIBLE (-2200 3300);
FORCEPROP 1 LAST PATH I41
J 2
(-1873 3425);
DISPLAY 0.872340 (-1873 3425);
PAINT GREEN (-1873 3425);
DISPLAY INVISIBLE (-1873 3425);
FORCEADD TAP..1
R 2
(-1875 3475);
FORCEPROP 3 LASTPIN (-1825 3475) SIG_NAME M_E_CPU0_SB_CA<1>
J 0
(-1815 3485);
DISPLAY 0.659574 (-1815 3485);
PAINT MONO (-1815 3485);
DISPLAY INVISIBLE (-1815 3485);
FORCEPROP 1 LASTPIN (-1825 3475) BN 1
J 2
(-1813 3483);
DISPLAY 0.680851 (-1813 3483);
PAINT GREEN (-1813 3483);
FORCEPROP 2 LAST CDS_LIB standard
J 0
(-1875 3475);
DISPLAY INVISIBLE (-1875 3475);
FORCEPROP 1 LAST BODY_TYPE PLUMBING
J 2
(-1875 3525);
DISPLAY 0.872340 (-1875 3525);
PAINT GREEN (-1875 3525);
DISPLAY INVISIBLE (-1875 3525);
FORCEPROP 1 LAST HDL_TAP TRUE
J 2
(-2200 3350);
DISPLAY 0.872340 (-2200 3350);
DISPLAY INVISIBLE (-2200 3350);
FORCEPROP 1 LAST PATH I42
J 2
(-1873 3475);
DISPLAY 0.872340 (-1873 3475);
PAINT GREEN (-1873 3475);
DISPLAY INVISIBLE (-1873 3475);
FORCEADD TAP..1
R 2
(-1875 3525);
FORCEPROP 3 LASTPIN (-1825 3525) SIG_NAME M_E_CPU0_SB_CA<2>
J 0
(-1815 3535);
DISPLAY 0.659574 (-1815 3535);
PAINT MONO (-1815 3535);
DISPLAY INVISIBLE (-1815 3535);
FORCEPROP 1 LASTPIN (-1825 3525) BN 2
J 2
(-1813 3533);
DISPLAY 0.680851 (-1813 3533);
PAINT GREEN (-1813 3533);
FORCEPROP 2 LAST CDS_LIB standard
J 0
(-1875 3525);
DISPLAY INVISIBLE (-1875 3525);
FORCEPROP 1 LAST BODY_TYPE PLUMBING
J 2
(-1875 3575);
DISPLAY 0.872340 (-1875 3575);
PAINT GREEN (-1875 3575);
DISPLAY INVISIBLE (-1875 3575);
FORCEPROP 1 LAST HDL_TAP TRUE
J 2
(-2200 3400);
DISPLAY 0.872340 (-2200 3400);
DISPLAY INVISIBLE (-2200 3400);
FORCEPROP 1 LAST PATH I43
J 2
(-1873 3525);
DISPLAY 0.872340 (-1873 3525);
PAINT GREEN (-1873 3525);
DISPLAY INVISIBLE (-1873 3525);
FORCEADD TAP..1
R 2
(-1875 3575);
FORCEPROP 3 LASTPIN (-1825 3575) SIG_NAME M_E_CPU0_SB_CA<3>
J 0
(-1815 3585);
DISPLAY 0.659574 (-1815 3585);
PAINT MONO (-1815 3585);
DISPLAY INVISIBLE (-1815 3585);
FORCEPROP 1 LASTPIN (-1825 3575) BN 3
J 2
(-1813 3583);
DISPLAY 0.680851 (-1813 3583);
PAINT GREEN (-1813 3583);
FORCEPROP 2 LAST CDS_LIB standard
J 0
(-1875 3575);
DISPLAY INVISIBLE (-1875 3575);
FORCEPROP 1 LAST BODY_TYPE PLUMBING
J 2
(-1875 3625);
DISPLAY 0.872340 (-1875 3625);
PAINT GREEN (-1875 3625);
DISPLAY INVISIBLE (-1875 3625);
FORCEPROP 1 LAST HDL_TAP TRUE
J 2
(-2200 3450);
DISPLAY 0.872340 (-2200 3450);
DISPLAY INVISIBLE (-2200 3450);
FORCEPROP 1 LAST PATH I44
J 2
(-1873 3575);
DISPLAY 0.872340 (-1873 3575);
PAINT GREEN (-1873 3575);
DISPLAY INVISIBLE (-1873 3575);
FORCEADD TAP..1
R 2
(-1875 3625);
FORCEPROP 3 LASTPIN (-1825 3625) SIG_NAME M_E_CPU0_SB_CA<4>
J 0
(-1815 3635);
DISPLAY 0.659574 (-1815 3635);
PAINT MONO (-1815 3635);
DISPLAY INVISIBLE (-1815 3635);
FORCEPROP 1 LASTPIN (-1825 3625) BN 4
J 2
(-1813 3633);
DISPLAY 0.680851 (-1813 3633);
PAINT GREEN (-1813 3633);
FORCEPROP 2 LAST CDS_LIB standard
J 0
(-1875 3625);
DISPLAY INVISIBLE (-1875 3625);
FORCEPROP 1 LAST BODY_TYPE PLUMBING
J 2
(-1875 3675);
DISPLAY 0.872340 (-1875 3675);
PAINT GREEN (-1875 3675);
DISPLAY INVISIBLE (-1875 3675);
FORCEPROP 1 LAST HDL_TAP TRUE
J 2
(-2200 3500);
DISPLAY 0.872340 (-2200 3500);
DISPLAY INVISIBLE (-2200 3500);
FORCEPROP 1 LAST PATH I45
J 2
(-1873 3625);
DISPLAY 0.872340 (-1873 3625);
PAINT GREEN (-1873 3625);
DISPLAY INVISIBLE (-1873 3625);
FORCEADD TAP..1
R 2
(-1875 3725);
FORCEPROP 3 LASTPIN (-1825 3725) SIG_NAME M_E_CPU0_SB_CA<6>
J 0
(-1815 3735);
DISPLAY 0.659574 (-1815 3735);
PAINT MONO (-1815 3735);
DISPLAY INVISIBLE (-1815 3735);
FORCEPROP 1 LASTPIN (-1825 3725) BN 6
J 2
(-1813 3733);
DISPLAY 0.680851 (-1813 3733);
PAINT GREEN (-1813 3733);
FORCEPROP 2 LAST CDS_LIB standard
J 0
(-1875 3725);
DISPLAY INVISIBLE (-1875 3725);
FORCEPROP 1 LAST BODY_TYPE PLUMBING
J 2
(-1875 3775);
DISPLAY 0.872340 (-1875 3775);
PAINT GREEN (-1875 3775);
DISPLAY INVISIBLE (-1875 3775);
FORCEPROP 1 LAST HDL_TAP TRUE
J 2
(-2200 3600);
DISPLAY 0.872340 (-2200 3600);
DISPLAY INVISIBLE (-2200 3600);
FORCEPROP 1 LAST PATH I46
J 2
(-1873 3725);
DISPLAY 0.872340 (-1873 3725);
PAINT GREEN (-1873 3725);
DISPLAY INVISIBLE (-1873 3725);
FORCEADD TAP..1
R 2
(-1875 3675);
FORCEPROP 3 LASTPIN (-1825 3675) SIG_NAME M_E_CPU0_SB_CA<5>
J 0
(-1815 3685);
DISPLAY 0.659574 (-1815 3685);
PAINT MONO (-1815 3685);
DISPLAY INVISIBLE (-1815 3685);
FORCEPROP 1 LASTPIN (-1825 3675) BN 5
J 2
(-1813 3683);
DISPLAY 0.680851 (-1813 3683);
PAINT GREEN (-1813 3683);
FORCEPROP 2 LAST CDS_LIB standard
J 0
(-1875 3675);
DISPLAY INVISIBLE (-1875 3675);
FORCEPROP 1 LAST BODY_TYPE PLUMBING
J 2
(-1875 3725);
DISPLAY 0.872340 (-1875 3725);
PAINT GREEN (-1875 3725);
DISPLAY INVISIBLE (-1875 3725);
FORCEPROP 1 LAST HDL_TAP TRUE
J 2
(-2200 3550);
DISPLAY 0.872340 (-2200 3550);
DISPLAY INVISIBLE (-2200 3550);
FORCEPROP 1 LAST PATH I47
J 2
(-1873 3675);
DISPLAY 0.872340 (-1873 3675);
PAINT GREEN (-1873 3675);
DISPLAY INVISIBLE (-1873 3675);
FORCEADD TAP..1
R 2
(-1875 3825);
FORCEPROP 3 LASTPIN (-1825 3825) SIG_NAME M_E_CPU0_SA_CA<0>
J 0
(-1815 3835);
DISPLAY 0.659574 (-1815 3835);
PAINT MONO (-1815 3835);
DISPLAY INVISIBLE (-1815 3835);
FORCEPROP 1 LASTPIN (-1825 3825) BN 0
J 2
(-1813 3833);
DISPLAY 0.680851 (-1813 3833);
PAINT GREEN (-1813 3833);
FORCEPROP 2 LAST CDS_LIB standard
J 0
(-1875 3825);
DISPLAY INVISIBLE (-1875 3825);
FORCEPROP 1 LAST BODY_TYPE PLUMBING
J 2
(-1875 3875);
DISPLAY 0.872340 (-1875 3875);
PAINT GREEN (-1875 3875);
DISPLAY INVISIBLE (-1875 3875);
FORCEPROP 1 LAST HDL_TAP TRUE
J 2
(-2200 3700);
DISPLAY 0.872340 (-2200 3700);
DISPLAY INVISIBLE (-2200 3700);
FORCEPROP 1 LAST PATH I48
J 2
(-1873 3825);
DISPLAY 0.872340 (-1873 3825);
PAINT GREEN (-1873 3825);
DISPLAY INVISIBLE (-1873 3825);
FORCEADD TAP..1
R 2
(-1875 3875);
FORCEPROP 3 LASTPIN (-1825 3875) SIG_NAME M_E_CPU0_SA_CA<1>
J 0
(-1815 3885);
DISPLAY 0.659574 (-1815 3885);
PAINT MONO (-1815 3885);
DISPLAY INVISIBLE (-1815 3885);
FORCEPROP 1 LASTPIN (-1825 3875) BN 1
J 2
(-1813 3883);
DISPLAY 0.680851 (-1813 3883);
PAINT GREEN (-1813 3883);
FORCEPROP 2 LAST CDS_LIB standard
J 0
(-1875 3875);
DISPLAY INVISIBLE (-1875 3875);
FORCEPROP 1 LAST BODY_TYPE PLUMBING
J 2
(-1875 3925);
DISPLAY 0.872340 (-1875 3925);
PAINT GREEN (-1875 3925);
DISPLAY INVISIBLE (-1875 3925);
FORCEPROP 1 LAST HDL_TAP TRUE
J 2
(-2200 3750);
DISPLAY 0.872340 (-2200 3750);
DISPLAY INVISIBLE (-2200 3750);
FORCEPROP 1 LAST PATH I49
J 2
(-1873 3875);
DISPLAY 0.872340 (-1873 3875);
PAINT GREEN (-1873 3875);
DISPLAY INVISIBLE (-1873 3875);
FORCEADD OFFPAGE..2
R 2
(-2800 675);
FORCEPROP 2 LAST $XR0 24 
J 0
(-3024 675);
DISPLAY 0.638298 (-3024 675);
PAINT MONO (-3024 675);
FORCEPROP 2 LAST CDS_LIB standard
J 0
(-2800 675);
PAINT MONO (-2800 675);
DISPLAY INVISIBLE (-2800 675);
FORCEPROP 1 LAST OFFPAGE TRUE
J 2
(-3125 550);
DISPLAY 0.872340 (-3125 550);
DISPLAY INVISIBLE (-3125 550);
FORCEPROP 1 LAST COMMENT_BODY TRUE
J 2
(-2755 580);
DISPLAY 0.872340 (-2755 580);
PAINT GREEN (-2755 580);
DISPLAY INVISIBLE (-2755 580);
FORCEPROP 2 LAST PATH I5
J 0
(-2750 750);
DISPLAY 1.021277 (-2750 750);
DISPLAY INVISIBLE (-2750 750);
FORCEADD TAP..1
R 2
(-1875 3925);
FORCEPROP 3 LASTPIN (-1825 3925) SIG_NAME M_E_CPU0_SA_CA<2>
J 0
(-1815 3935);
DISPLAY 0.659574 (-1815 3935);
PAINT MONO (-1815 3935);
DISPLAY INVISIBLE (-1815 3935);
FORCEPROP 1 LASTPIN (-1825 3925) BN 2
J 2
(-1813 3933);
DISPLAY 0.680851 (-1813 3933);
PAINT GREEN (-1813 3933);
FORCEPROP 2 LAST CDS_LIB standard
J 0
(-1875 3925);
DISPLAY INVISIBLE (-1875 3925);
FORCEPROP 1 LAST BODY_TYPE PLUMBING
J 2
(-1875 3975);
DISPLAY 0.872340 (-1875 3975);
PAINT GREEN (-1875 3975);
DISPLAY INVISIBLE (-1875 3975);
FORCEPROP 1 LAST HDL_TAP TRUE
J 2
(-2200 3800);
DISPLAY 0.872340 (-2200 3800);
DISPLAY INVISIBLE (-2200 3800);
FORCEPROP 1 LAST PATH I50
J 2
(-1873 3925);
DISPLAY 0.872340 (-1873 3925);
PAINT GREEN (-1873 3925);
DISPLAY INVISIBLE (-1873 3925);
FORCEADD TAP..1
R 2
(-1875 3975);
FORCEPROP 3 LASTPIN (-1825 3975) SIG_NAME M_E_CPU0_SA_CA<3>
J 0
(-1815 3985);
DISPLAY 0.659574 (-1815 3985);
PAINT MONO (-1815 3985);
DISPLAY INVISIBLE (-1815 3985);
FORCEPROP 1 LASTPIN (-1825 3975) BN 3
J 2
(-1813 3983);
DISPLAY 0.680851 (-1813 3983);
PAINT GREEN (-1813 3983);
FORCEPROP 2 LAST CDS_LIB standard
J 0
(-1875 3975);
DISPLAY INVISIBLE (-1875 3975);
FORCEPROP 1 LAST BODY_TYPE PLUMBING
J 2
(-1875 4025);
DISPLAY 0.872340 (-1875 4025);
PAINT GREEN (-1875 4025);
DISPLAY INVISIBLE (-1875 4025);
FORCEPROP 1 LAST HDL_TAP TRUE
J 2
(-2200 3850);
DISPLAY 0.872340 (-2200 3850);
DISPLAY INVISIBLE (-2200 3850);
FORCEPROP 1 LAST PATH I51
J 2
(-1873 3975);
DISPLAY 0.872340 (-1873 3975);
PAINT GREEN (-1873 3975);
DISPLAY INVISIBLE (-1873 3975);
FORCEADD TAP..1
(-225 925);
FORCEPROP 3 LASTPIN (-275 925) SIG_NAME M_E_CPU0_SB_DQ<0>
J 0
(-265 935);
DISPLAY 0.659574 (-265 935);
PAINT MONO (-265 935);
DISPLAY INVISIBLE (-265 935);
FORCEPROP 1 LASTPIN (-275 925) BN 0
J 0
(-287 933);
DISPLAY 0.680851 (-287 933);
PAINT GREEN (-287 933);
FORCEPROP 2 LAST CDS_LIB standard
J 0
(-225 925);
PAINT MONO (-225 925);
DISPLAY INVISIBLE (-225 925);
FORCEPROP 1 LAST BODY_TYPE PLUMBING
J 0
(-225 975);
DISPLAY 0.872340 (-225 975);
PAINT GREEN (-225 975);
DISPLAY INVISIBLE (-225 975);
FORCEPROP 1 LAST HDL_TAP TRUE
J 0
(100 800);
DISPLAY 0.872340 (100 800);
DISPLAY INVISIBLE (100 800);
FORCEPROP 1 LAST PATH I52
J 0
(-227 925);
DISPLAY 0.872340 (-227 925);
PAINT GREEN (-227 925);
DISPLAY INVISIBLE (-227 925);
FORCEADD TAP..1
(-225 975);
FORCEPROP 3 LASTPIN (-275 975) SIG_NAME M_E_CPU0_SB_DQ<1>
J 0
(-265 985);
DISPLAY 0.659574 (-265 985);
PAINT MONO (-265 985);
DISPLAY INVISIBLE (-265 985);
FORCEPROP 1 LASTPIN (-275 975) BN 1
J 0
(-287 983);
DISPLAY 0.680851 (-287 983);
PAINT GREEN (-287 983);
FORCEPROP 2 LAST CDS_LIB standard
J 0
(-225 975);
PAINT MONO (-225 975);
DISPLAY INVISIBLE (-225 975);
FORCEPROP 1 LAST BODY_TYPE PLUMBING
J 0
(-225 1025);
DISPLAY 0.872340 (-225 1025);
PAINT GREEN (-225 1025);
DISPLAY INVISIBLE (-225 1025);
FORCEPROP 1 LAST HDL_TAP TRUE
J 0
(100 850);
DISPLAY 0.872340 (100 850);
DISPLAY INVISIBLE (100 850);
FORCEPROP 1 LAST PATH I53
J 0
(-227 975);
DISPLAY 0.872340 (-227 975);
PAINT GREEN (-227 975);
DISPLAY INVISIBLE (-227 975);
FORCEADD TAP..1
(-225 1075);
FORCEPROP 3 LASTPIN (-275 1075) SIG_NAME M_E_CPU0_SB_DQ<3>
J 0
(-265 1085);
DISPLAY 0.659574 (-265 1085);
PAINT MONO (-265 1085);
DISPLAY INVISIBLE (-265 1085);
FORCEPROP 1 LASTPIN (-275 1075) BN 3
J 0
(-287 1083);
DISPLAY 0.680851 (-287 1083);
PAINT GREEN (-287 1083);
FORCEPROP 2 LAST CDS_LIB standard
J 0
(-225 1075);
PAINT MONO (-225 1075);
DISPLAY INVISIBLE (-225 1075);
FORCEPROP 1 LAST BODY_TYPE PLUMBING
J 0
(-225 1125);
DISPLAY 0.872340 (-225 1125);
PAINT GREEN (-225 1125);
DISPLAY INVISIBLE (-225 1125);
FORCEPROP 1 LAST HDL_TAP TRUE
J 0
(100 950);
DISPLAY 0.872340 (100 950);
DISPLAY INVISIBLE (100 950);
FORCEPROP 1 LAST PATH I54
J 0
(-227 1075);
DISPLAY 0.872340 (-227 1075);
PAINT GREEN (-227 1075);
DISPLAY INVISIBLE (-227 1075);
FORCEADD TAP..1
(-225 1025);
FORCEPROP 3 LASTPIN (-275 1025) SIG_NAME M_E_CPU0_SB_DQ<2>
J 0
(-265 1035);
DISPLAY 0.659574 (-265 1035);
PAINT MONO (-265 1035);
DISPLAY INVISIBLE (-265 1035);
FORCEPROP 1 LASTPIN (-275 1025) BN 2
J 0
(-287 1033);
DISPLAY 0.680851 (-287 1033);
PAINT GREEN (-287 1033);
FORCEPROP 2 LAST CDS_LIB standard
J 0
(-225 1025);
PAINT MONO (-225 1025);
DISPLAY INVISIBLE (-225 1025);
FORCEPROP 1 LAST BODY_TYPE PLUMBING
J 0
(-225 1075);
DISPLAY 0.872340 (-225 1075);
PAINT GREEN (-225 1075);
DISPLAY INVISIBLE (-225 1075);
FORCEPROP 1 LAST HDL_TAP TRUE
J 0
(100 900);
DISPLAY 0.872340 (100 900);
DISPLAY INVISIBLE (100 900);
FORCEPROP 1 LAST PATH I55
J 0
(-227 1025);
DISPLAY 0.872340 (-227 1025);
PAINT GREEN (-227 1025);
DISPLAY INVISIBLE (-227 1025);
FORCEADD TAP..1
(-225 1125);
FORCEPROP 3 LASTPIN (-275 1125) SIG_NAME M_E_CPU0_SB_DQ<4>
J 0
(-265 1135);
DISPLAY 0.659574 (-265 1135);
PAINT MONO (-265 1135);
DISPLAY INVISIBLE (-265 1135);
FORCEPROP 1 LASTPIN (-275 1125) BN 4
J 0
(-287 1133);
DISPLAY 0.680851 (-287 1133);
PAINT GREEN (-287 1133);
FORCEPROP 2 LAST CDS_LIB standard
J 0
(-225 1125);
PAINT MONO (-225 1125);
DISPLAY INVISIBLE (-225 1125);
FORCEPROP 1 LAST BODY_TYPE PLUMBING
J 0
(-225 1175);
DISPLAY 0.872340 (-225 1175);
PAINT GREEN (-225 1175);
DISPLAY INVISIBLE (-225 1175);
FORCEPROP 1 LAST HDL_TAP TRUE
J 0
(100 1000);
DISPLAY 0.872340 (100 1000);
DISPLAY INVISIBLE (100 1000);
FORCEPROP 1 LAST PATH I56
J 0
(-227 1125);
DISPLAY 0.872340 (-227 1125);
PAINT GREEN (-227 1125);
DISPLAY INVISIBLE (-227 1125);
FORCEADD TAP..1
(-225 1175);
FORCEPROP 3 LASTPIN (-275 1175) SIG_NAME M_E_CPU0_SB_DQ<5>
J 0
(-265 1185);
DISPLAY 0.659574 (-265 1185);
PAINT MONO (-265 1185);
DISPLAY INVISIBLE (-265 1185);
FORCEPROP 1 LASTPIN (-275 1175) BN 5
J 0
(-287 1183);
DISPLAY 0.680851 (-287 1183);
PAINT GREEN (-287 1183);
FORCEPROP 2 LAST CDS_LIB standard
J 0
(-225 1175);
PAINT MONO (-225 1175);
DISPLAY INVISIBLE (-225 1175);
FORCEPROP 1 LAST BODY_TYPE PLUMBING
J 0
(-225 1225);
DISPLAY 0.872340 (-225 1225);
PAINT GREEN (-225 1225);
DISPLAY INVISIBLE (-225 1225);
FORCEPROP 1 LAST HDL_TAP TRUE
J 0
(100 1050);
DISPLAY 0.872340 (100 1050);
DISPLAY INVISIBLE (100 1050);
FORCEPROP 1 LAST PATH I57
J 0
(-227 1175);
DISPLAY 0.872340 (-227 1175);
PAINT GREEN (-227 1175);
DISPLAY INVISIBLE (-227 1175);
FORCEADD TAP..1
(-225 1225);
FORCEPROP 3 LASTPIN (-275 1225) SIG_NAME M_E_CPU0_SB_DQ<6>
J 0
(-265 1235);
DISPLAY 0.659574 (-265 1235);
PAINT MONO (-265 1235);
DISPLAY INVISIBLE (-265 1235);
FORCEPROP 1 LASTPIN (-275 1225) BN 6
J 0
(-287 1233);
DISPLAY 0.680851 (-287 1233);
PAINT GREEN (-287 1233);
FORCEPROP 2 LAST CDS_LIB standard
J 0
(-225 1225);
PAINT MONO (-225 1225);
DISPLAY INVISIBLE (-225 1225);
FORCEPROP 1 LAST BODY_TYPE PLUMBING
J 0
(-225 1275);
DISPLAY 0.872340 (-225 1275);
PAINT GREEN (-225 1275);
DISPLAY INVISIBLE (-225 1275);
FORCEPROP 1 LAST HDL_TAP TRUE
J 0
(100 1100);
DISPLAY 0.872340 (100 1100);
DISPLAY INVISIBLE (100 1100);
FORCEPROP 1 LAST PATH I58
J 0
(-227 1225);
DISPLAY 0.872340 (-227 1225);
PAINT GREEN (-227 1225);
DISPLAY INVISIBLE (-227 1225);
FORCEADD TAP..1
(-225 1325);
FORCEPROP 3 LASTPIN (-275 1325) SIG_NAME M_E_CPU0_SB_DQ<8>
J 0
(-265 1335);
DISPLAY 0.659574 (-265 1335);
PAINT MONO (-265 1335);
DISPLAY INVISIBLE (-265 1335);
FORCEPROP 1 LASTPIN (-275 1325) BN 8
J 0
(-287 1333);
DISPLAY 0.680851 (-287 1333);
PAINT GREEN (-287 1333);
FORCEPROP 2 LAST CDS_LIB standard
J 0
(-225 1325);
PAINT MONO (-225 1325);
DISPLAY INVISIBLE (-225 1325);
FORCEPROP 1 LAST BODY_TYPE PLUMBING
J 0
(-225 1375);
DISPLAY 0.872340 (-225 1375);
PAINT GREEN (-225 1375);
DISPLAY INVISIBLE (-225 1375);
FORCEPROP 1 LAST HDL_TAP TRUE
J 0
(100 1200);
DISPLAY 0.872340 (100 1200);
DISPLAY INVISIBLE (100 1200);
FORCEPROP 1 LAST PATH I59
J 0
(-227 1325);
DISPLAY 0.872340 (-227 1325);
PAINT GREEN (-227 1325);
DISPLAY INVISIBLE (-227 1325);
FORCEADD OFFPAGE..3
R 2
(-2800 1275);
FORCEPROP 2 LAST $XR0 114 
J 0
(-3080 1275);
DISPLAY 0.638298 (-3080 1275);
PAINT MONO (-3080 1275);
FORCEPROP 2 LAST CDS_LIB standard
J 0
(-2800 1275);
PAINT MONO (-2800 1275);
DISPLAY INVISIBLE (-2800 1275);
FORCEPROP 1 LAST OFFPAGE TRUE
J 2
(-3125 1150);
DISPLAY 0.872340 (-3125 1150);
DISPLAY INVISIBLE (-3125 1150);
FORCEPROP 1 LAST COMMENT_BODY TRUE
J 2
(-2750 1175);
DISPLAY 0.872340 (-2750 1175);
PAINT GREEN (-2750 1175);
DISPLAY INVISIBLE (-2750 1175);
FORCEPROP 2 LAST PATH I6
J 0
(-2750 1350);
DISPLAY 1.021277 (-2750 1350);
DISPLAY INVISIBLE (-2750 1350);
FORCEADD TAP..1
(-225 1275);
FORCEPROP 3 LASTPIN (-275 1275) SIG_NAME M_E_CPU0_SB_DQ<7>
J 0
(-265 1285);
DISPLAY 0.659574 (-265 1285);
PAINT MONO (-265 1285);
DISPLAY INVISIBLE (-265 1285);
FORCEPROP 1 LASTPIN (-275 1275) BN 7
J 0
(-287 1283);
DISPLAY 0.680851 (-287 1283);
PAINT GREEN (-287 1283);
FORCEPROP 2 LAST CDS_LIB standard
J 0
(-225 1275);
PAINT MONO (-225 1275);
DISPLAY INVISIBLE (-225 1275);
FORCEPROP 1 LAST BODY_TYPE PLUMBING
J 0
(-225 1325);
DISPLAY 0.872340 (-225 1325);
PAINT GREEN (-225 1325);
DISPLAY INVISIBLE (-225 1325);
FORCEPROP 1 LAST HDL_TAP TRUE
J 0
(100 1150);
DISPLAY 0.872340 (100 1150);
DISPLAY INVISIBLE (100 1150);
FORCEPROP 1 LAST PATH I60
J 0
(-227 1275);
DISPLAY 0.872340 (-227 1275);
PAINT GREEN (-227 1275);
DISPLAY INVISIBLE (-227 1275);
FORCEADD TAP..1
(-225 1375);
FORCEPROP 3 LASTPIN (-275 1375) SIG_NAME M_E_CPU0_SB_DQ<9>
J 0
(-265 1385);
DISPLAY 0.659574 (-265 1385);
PAINT MONO (-265 1385);
DISPLAY INVISIBLE (-265 1385);
FORCEPROP 1 LASTPIN (-275 1375) BN 9
J 0
(-287 1383);
DISPLAY 0.680851 (-287 1383);
PAINT GREEN (-287 1383);
FORCEPROP 2 LAST CDS_LIB standard
J 0
(-225 1375);
PAINT MONO (-225 1375);
DISPLAY INVISIBLE (-225 1375);
FORCEPROP 1 LAST BODY_TYPE PLUMBING
J 0
(-225 1425);
DISPLAY 0.872340 (-225 1425);
PAINT GREEN (-225 1425);
DISPLAY INVISIBLE (-225 1425);
FORCEPROP 1 LAST HDL_TAP TRUE
J 0
(100 1250);
DISPLAY 0.872340 (100 1250);
DISPLAY INVISIBLE (100 1250);
FORCEPROP 1 LAST PATH I61
J 0
(-227 1375);
DISPLAY 0.872340 (-227 1375);
PAINT GREEN (-227 1375);
DISPLAY INVISIBLE (-227 1375);
FORCEADD TAP..1
(-225 1425);
FORCEPROP 3 LASTPIN (-275 1425) SIG_NAME M_E_CPU0_SB_DQ<10>
J 0
(-265 1435);
DISPLAY 0.659574 (-265 1435);
PAINT MONO (-265 1435);
DISPLAY INVISIBLE (-265 1435);
FORCEPROP 1 LASTPIN (-275 1425) BN 10
J 0
(-287 1433);
DISPLAY 0.680851 (-287 1433);
PAINT GREEN (-287 1433);
FORCEPROP 2 LAST CDS_LIB standard
J 0
(-225 1425);
PAINT MONO (-225 1425);
DISPLAY INVISIBLE (-225 1425);
FORCEPROP 1 LAST BODY_TYPE PLUMBING
J 0
(-225 1475);
DISPLAY 0.872340 (-225 1475);
PAINT GREEN (-225 1475);
DISPLAY INVISIBLE (-225 1475);
FORCEPROP 1 LAST HDL_TAP TRUE
J 0
(100 1300);
DISPLAY 0.872340 (100 1300);
DISPLAY INVISIBLE (100 1300);
FORCEPROP 1 LAST PATH I62
J 0
(-227 1425);
DISPLAY 0.872340 (-227 1425);
PAINT GREEN (-227 1425);
DISPLAY INVISIBLE (-227 1425);
FORCEADD TAP..1
(-225 1475);
FORCEPROP 3 LASTPIN (-275 1475) SIG_NAME M_E_CPU0_SB_DQ<11>
J 0
(-265 1485);
DISPLAY 0.659574 (-265 1485);
PAINT MONO (-265 1485);
DISPLAY INVISIBLE (-265 1485);
FORCEPROP 1 LASTPIN (-275 1475) BN 11
J 0
(-287 1483);
DISPLAY 0.680851 (-287 1483);
PAINT GREEN (-287 1483);
FORCEPROP 2 LAST CDS_LIB standard
J 0
(-225 1475);
PAINT MONO (-225 1475);
DISPLAY INVISIBLE (-225 1475);
FORCEPROP 1 LAST BODY_TYPE PLUMBING
J 0
(-225 1525);
DISPLAY 0.872340 (-225 1525);
PAINT GREEN (-225 1525);
DISPLAY INVISIBLE (-225 1525);
FORCEPROP 1 LAST HDL_TAP TRUE
J 0
(100 1350);
DISPLAY 0.872340 (100 1350);
DISPLAY INVISIBLE (100 1350);
FORCEPROP 1 LAST PATH I63
J 0
(-227 1475);
DISPLAY 0.872340 (-227 1475);
PAINT GREEN (-227 1475);
DISPLAY INVISIBLE (-227 1475);
FORCEADD TAP..1
(-225 1525);
FORCEPROP 3 LASTPIN (-275 1525) SIG_NAME M_E_CPU0_SB_DQ<12>
J 0
(-265 1535);
DISPLAY 0.659574 (-265 1535);
PAINT MONO (-265 1535);
DISPLAY INVISIBLE (-265 1535);
FORCEPROP 1 LASTPIN (-275 1525) BN 12
J 0
(-287 1533);
DISPLAY 0.680851 (-287 1533);
PAINT GREEN (-287 1533);
FORCEPROP 2 LAST CDS_LIB standard
J 0
(-225 1525);
PAINT MONO (-225 1525);
DISPLAY INVISIBLE (-225 1525);
FORCEPROP 1 LAST BODY_TYPE PLUMBING
J 0
(-225 1575);
DISPLAY 0.872340 (-225 1575);
PAINT GREEN (-225 1575);
DISPLAY INVISIBLE (-225 1575);
FORCEPROP 1 LAST HDL_TAP TRUE
J 0
(100 1400);
DISPLAY 0.872340 (100 1400);
DISPLAY INVISIBLE (100 1400);
FORCEPROP 1 LAST PATH I64
J 0
(-227 1525);
DISPLAY 0.872340 (-227 1525);
PAINT GREEN (-227 1525);
DISPLAY INVISIBLE (-227 1525);
FORCEADD TAP..1
(-225 1575);
FORCEPROP 3 LASTPIN (-275 1575) SIG_NAME M_E_CPU0_SB_DQ<13>
J 0
(-265 1585);
DISPLAY 0.659574 (-265 1585);
PAINT MONO (-265 1585);
DISPLAY INVISIBLE (-265 1585);
FORCEPROP 1 LASTPIN (-275 1575) BN 13
J 0
(-287 1583);
DISPLAY 0.680851 (-287 1583);
PAINT GREEN (-287 1583);
FORCEPROP 2 LAST CDS_LIB standard
J 0
(-225 1575);
PAINT MONO (-225 1575);
DISPLAY INVISIBLE (-225 1575);
FORCEPROP 1 LAST BODY_TYPE PLUMBING
J 0
(-225 1625);
DISPLAY 0.872340 (-225 1625);
PAINT GREEN (-225 1625);
DISPLAY INVISIBLE (-225 1625);
FORCEPROP 1 LAST HDL_TAP TRUE
J 0
(100 1450);
DISPLAY 0.872340 (100 1450);
DISPLAY INVISIBLE (100 1450);
FORCEPROP 1 LAST PATH I65
J 0
(-227 1575);
DISPLAY 0.872340 (-227 1575);
PAINT GREEN (-227 1575);
DISPLAY INVISIBLE (-227 1575);
FORCEADD TAP..1
(-225 1625);
FORCEPROP 3 LASTPIN (-275 1625) SIG_NAME M_E_CPU0_SB_DQ<14>
J 0
(-265 1635);
DISPLAY 0.659574 (-265 1635);
PAINT MONO (-265 1635);
DISPLAY INVISIBLE (-265 1635);
FORCEPROP 1 LASTPIN (-275 1625) BN 14
J 0
(-287 1633);
DISPLAY 0.680851 (-287 1633);
PAINT GREEN (-287 1633);
FORCEPROP 2 LAST CDS_LIB standard
J 0
(-225 1625);
PAINT MONO (-225 1625);
DISPLAY INVISIBLE (-225 1625);
FORCEPROP 1 LAST BODY_TYPE PLUMBING
J 0
(-225 1675);
DISPLAY 0.872340 (-225 1675);
PAINT GREEN (-225 1675);
DISPLAY INVISIBLE (-225 1675);
FORCEPROP 1 LAST HDL_TAP TRUE
J 0
(100 1500);
DISPLAY 0.872340 (100 1500);
DISPLAY INVISIBLE (100 1500);
FORCEPROP 1 LAST PATH I66
J 0
(-227 1625);
DISPLAY 0.872340 (-227 1625);
PAINT GREEN (-227 1625);
DISPLAY INVISIBLE (-227 1625);
FORCEADD TAP..1
(-225 1675);
FORCEPROP 3 LASTPIN (-275 1675) SIG_NAME M_E_CPU0_SB_DQ<15>
J 0
(-265 1685);
DISPLAY 0.659574 (-265 1685);
PAINT MONO (-265 1685);
DISPLAY INVISIBLE (-265 1685);
FORCEPROP 1 LASTPIN (-275 1675) BN 15
J 0
(-287 1683);
DISPLAY 0.680851 (-287 1683);
PAINT GREEN (-287 1683);
FORCEPROP 2 LAST CDS_LIB standard
J 0
(-225 1675);
PAINT MONO (-225 1675);
DISPLAY INVISIBLE (-225 1675);
FORCEPROP 1 LAST BODY_TYPE PLUMBING
J 0
(-225 1725);
DISPLAY 0.872340 (-225 1725);
PAINT GREEN (-225 1725);
DISPLAY INVISIBLE (-225 1725);
FORCEPROP 1 LAST HDL_TAP TRUE
J 0
(100 1550);
DISPLAY 0.872340 (100 1550);
DISPLAY INVISIBLE (100 1550);
FORCEPROP 1 LAST PATH I67
J 0
(-227 1675);
DISPLAY 0.872340 (-227 1675);
PAINT GREEN (-227 1675);
DISPLAY INVISIBLE (-227 1675);
FORCEADD TAP..1
(-225 1775);
FORCEPROP 3 LASTPIN (-275 1775) SIG_NAME M_E_CPU0_SB_DQ<17>
J 0
(-265 1785);
DISPLAY 0.659574 (-265 1785);
PAINT MONO (-265 1785);
DISPLAY INVISIBLE (-265 1785);
FORCEPROP 1 LASTPIN (-275 1775) BN 17
J 0
(-287 1783);
DISPLAY 0.680851 (-287 1783);
PAINT GREEN (-287 1783);
FORCEPROP 2 LAST CDS_LIB standard
J 0
(-225 1775);
PAINT MONO (-225 1775);
DISPLAY INVISIBLE (-225 1775);
FORCEPROP 1 LAST BODY_TYPE PLUMBING
J 0
(-225 1825);
DISPLAY 0.872340 (-225 1825);
PAINT GREEN (-225 1825);
DISPLAY INVISIBLE (-225 1825);
FORCEPROP 1 LAST HDL_TAP TRUE
J 0
(100 1650);
DISPLAY 0.872340 (100 1650);
DISPLAY INVISIBLE (100 1650);
FORCEPROP 1 LAST PATH I68
J 0
(-227 1775);
DISPLAY 0.872340 (-227 1775);
PAINT GREEN (-227 1775);
DISPLAY INVISIBLE (-227 1775);
FORCEADD TAP..1
(-225 1725);
FORCEPROP 3 LASTPIN (-275 1725) SIG_NAME M_E_CPU0_SB_DQ<16>
J 0
(-265 1735);
DISPLAY 0.659574 (-265 1735);
PAINT MONO (-265 1735);
DISPLAY INVISIBLE (-265 1735);
FORCEPROP 1 LASTPIN (-275 1725) BN 16
J 0
(-287 1733);
DISPLAY 0.680851 (-287 1733);
PAINT GREEN (-287 1733);
FORCEPROP 2 LAST CDS_LIB standard
J 0
(-225 1725);
PAINT MONO (-225 1725);
DISPLAY INVISIBLE (-225 1725);
FORCEPROP 1 LAST BODY_TYPE PLUMBING
J 0
(-225 1775);
DISPLAY 0.872340 (-225 1775);
PAINT GREEN (-225 1775);
DISPLAY INVISIBLE (-225 1775);
FORCEPROP 1 LAST HDL_TAP TRUE
J 0
(100 1600);
DISPLAY 0.872340 (100 1600);
DISPLAY INVISIBLE (100 1600);
FORCEPROP 1 LAST PATH I69
J 0
(-227 1725);
DISPLAY 0.872340 (-227 1725);
PAINT GREEN (-227 1725);
DISPLAY INVISIBLE (-227 1725);
FORCEADD TAP..1
(-225 1825);
FORCEPROP 3 LASTPIN (-275 1825) SIG_NAME M_E_CPU0_SB_DQ<18>
J 0
(-265 1835);
DISPLAY 0.659574 (-265 1835);
PAINT MONO (-265 1835);
DISPLAY INVISIBLE (-265 1835);
FORCEPROP 1 LASTPIN (-275 1825) BN 18
J 0
(-287 1833);
DISPLAY 0.680851 (-287 1833);
PAINT GREEN (-287 1833);
FORCEPROP 2 LAST CDS_LIB standard
J 0
(-225 1825);
PAINT MONO (-225 1825);
DISPLAY INVISIBLE (-225 1825);
FORCEPROP 1 LAST BODY_TYPE PLUMBING
J 0
(-225 1875);
DISPLAY 0.872340 (-225 1875);
PAINT GREEN (-225 1875);
DISPLAY INVISIBLE (-225 1875);
FORCEPROP 1 LAST HDL_TAP TRUE
J 0
(100 1700);
DISPLAY 0.872340 (100 1700);
DISPLAY INVISIBLE (100 1700);
FORCEPROP 1 LAST PATH I70
J 0
(-227 1825);
DISPLAY 0.872340 (-227 1825);
PAINT GREEN (-227 1825);
DISPLAY INVISIBLE (-227 1825);
FORCEADD TAP..1
(-225 1875);
FORCEPROP 3 LASTPIN (-275 1875) SIG_NAME M_E_CPU0_SB_DQ<19>
J 0
(-265 1885);
DISPLAY 0.659574 (-265 1885);
PAINT MONO (-265 1885);
DISPLAY INVISIBLE (-265 1885);
FORCEPROP 1 LASTPIN (-275 1875) BN 19
J 0
(-287 1883);
DISPLAY 0.680851 (-287 1883);
PAINT GREEN (-287 1883);
FORCEPROP 2 LAST CDS_LIB standard
J 0
(-225 1875);
PAINT MONO (-225 1875);
DISPLAY INVISIBLE (-225 1875);
FORCEPROP 1 LAST BODY_TYPE PLUMBING
J 0
(-225 1925);
DISPLAY 0.872340 (-225 1925);
PAINT GREEN (-225 1925);
DISPLAY INVISIBLE (-225 1925);
FORCEPROP 1 LAST HDL_TAP TRUE
J 0
(100 1750);
DISPLAY 0.872340 (100 1750);
DISPLAY INVISIBLE (100 1750);
FORCEPROP 1 LAST PATH I71
J 0
(-227 1875);
DISPLAY 0.872340 (-227 1875);
PAINT GREEN (-227 1875);
DISPLAY INVISIBLE (-227 1875);
FORCEADD TAP..1
(-225 1925);
FORCEPROP 3 LASTPIN (-275 1925) SIG_NAME M_E_CPU0_SB_DQ<20>
J 0
(-265 1935);
DISPLAY 0.659574 (-265 1935);
PAINT MONO (-265 1935);
DISPLAY INVISIBLE (-265 1935);
FORCEPROP 1 LASTPIN (-275 1925) BN 20
J 0
(-287 1933);
DISPLAY 0.680851 (-287 1933);
PAINT GREEN (-287 1933);
FORCEPROP 2 LAST CDS_LIB standard
J 0
(-225 1925);
PAINT MONO (-225 1925);
DISPLAY INVISIBLE (-225 1925);
FORCEPROP 1 LAST BODY_TYPE PLUMBING
J 0
(-225 1975);
DISPLAY 0.872340 (-225 1975);
PAINT GREEN (-225 1975);
DISPLAY INVISIBLE (-225 1975);
FORCEPROP 1 LAST HDL_TAP TRUE
J 0
(100 1800);
DISPLAY 0.872340 (100 1800);
DISPLAY INVISIBLE (100 1800);
FORCEPROP 1 LAST PATH I72
J 0
(-227 1925);
DISPLAY 0.872340 (-227 1925);
PAINT GREEN (-227 1925);
DISPLAY INVISIBLE (-227 1925);
FORCEADD TAP..1
(-225 1975);
FORCEPROP 3 LASTPIN (-275 1975) SIG_NAME M_E_CPU0_SB_DQ<21>
J 0
(-265 1985);
DISPLAY 0.659574 (-265 1985);
PAINT MONO (-265 1985);
DISPLAY INVISIBLE (-265 1985);
FORCEPROP 1 LASTPIN (-275 1975) BN 21
J 0
(-287 1983);
DISPLAY 0.680851 (-287 1983);
PAINT GREEN (-287 1983);
FORCEPROP 2 LAST CDS_LIB standard
J 0
(-225 1975);
PAINT MONO (-225 1975);
DISPLAY INVISIBLE (-225 1975);
FORCEPROP 1 LAST BODY_TYPE PLUMBING
J 0
(-225 2025);
DISPLAY 0.872340 (-225 2025);
PAINT GREEN (-225 2025);
DISPLAY INVISIBLE (-225 2025);
FORCEPROP 1 LAST HDL_TAP TRUE
J 0
(100 1850);
DISPLAY 0.872340 (100 1850);
DISPLAY INVISIBLE (100 1850);
FORCEPROP 1 LAST PATH I73
J 0
(-227 1975);
DISPLAY 0.872340 (-227 1975);
PAINT GREEN (-227 1975);
DISPLAY INVISIBLE (-227 1975);
FORCEADD TAP..1
(-225 2025);
FORCEPROP 3 LASTPIN (-275 2025) SIG_NAME M_E_CPU0_SB_DQ<22>
J 0
(-265 2035);
DISPLAY 0.659574 (-265 2035);
PAINT MONO (-265 2035);
DISPLAY INVISIBLE (-265 2035);
FORCEPROP 1 LASTPIN (-275 2025) BN 22
J 0
(-287 2033);
DISPLAY 0.680851 (-287 2033);
PAINT GREEN (-287 2033);
FORCEPROP 2 LAST CDS_LIB standard
J 0
(-225 2025);
DISPLAY INVISIBLE (-225 2025);
FORCEPROP 1 LAST BODY_TYPE PLUMBING
J 0
(-225 2075);
DISPLAY 0.872340 (-225 2075);
PAINT GREEN (-225 2075);
DISPLAY INVISIBLE (-225 2075);
FORCEPROP 1 LAST HDL_TAP TRUE
J 0
(100 1900);
DISPLAY 0.872340 (100 1900);
DISPLAY INVISIBLE (100 1900);
FORCEPROP 1 LAST PATH I74
J 0
(-227 2025);
DISPLAY 0.872340 (-227 2025);
PAINT GREEN (-227 2025);
DISPLAY INVISIBLE (-227 2025);
FORCEADD TAP..1
(-225 2075);
FORCEPROP 3 LASTPIN (-275 2075) SIG_NAME M_E_CPU0_SB_DQ<23>
J 0
(-265 2085);
DISPLAY 0.659574 (-265 2085);
PAINT MONO (-265 2085);
DISPLAY INVISIBLE (-265 2085);
FORCEPROP 1 LASTPIN (-275 2075) BN 23
J 0
(-287 2083);
DISPLAY 0.680851 (-287 2083);
PAINT GREEN (-287 2083);
FORCEPROP 2 LAST CDS_LIB standard
J 0
(-225 2075);
DISPLAY INVISIBLE (-225 2075);
FORCEPROP 1 LAST BODY_TYPE PLUMBING
J 0
(-225 2125);
DISPLAY 0.872340 (-225 2125);
PAINT GREEN (-225 2125);
DISPLAY INVISIBLE (-225 2125);
FORCEPROP 1 LAST HDL_TAP TRUE
J 0
(100 1950);
DISPLAY 0.872340 (100 1950);
DISPLAY INVISIBLE (100 1950);
FORCEPROP 1 LAST PATH I75
J 0
(-227 2075);
DISPLAY 0.872340 (-227 2075);
PAINT GREEN (-227 2075);
DISPLAY INVISIBLE (-227 2075);
FORCEADD TAP..1
(-225 2125);
FORCEPROP 3 LASTPIN (-275 2125) SIG_NAME M_E_CPU0_SB_DQ<24>
J 0
(-265 2135);
DISPLAY 0.659574 (-265 2135);
PAINT MONO (-265 2135);
DISPLAY INVISIBLE (-265 2135);
FORCEPROP 1 LASTPIN (-275 2125) BN 24
J 0
(-287 2133);
DISPLAY 0.680851 (-287 2133);
PAINT GREEN (-287 2133);
FORCEPROP 2 LAST CDS_LIB standard
J 0
(-225 2125);
DISPLAY INVISIBLE (-225 2125);
FORCEPROP 1 LAST BODY_TYPE PLUMBING
J 0
(-225 2175);
DISPLAY 0.872340 (-225 2175);
PAINT GREEN (-225 2175);
DISPLAY INVISIBLE (-225 2175);
FORCEPROP 1 LAST HDL_TAP TRUE
J 0
(100 2000);
DISPLAY 0.872340 (100 2000);
DISPLAY INVISIBLE (100 2000);
FORCEPROP 1 LAST PATH I76
J 0
(-227 2125);
DISPLAY 0.872340 (-227 2125);
PAINT GREEN (-227 2125);
DISPLAY INVISIBLE (-227 2125);
FORCEADD TAP..1
(-225 2225);
FORCEPROP 3 LASTPIN (-275 2225) SIG_NAME M_E_CPU0_SB_DQ<26>
J 0
(-265 2235);
DISPLAY 0.659574 (-265 2235);
PAINT MONO (-265 2235);
DISPLAY INVISIBLE (-265 2235);
FORCEPROP 1 LASTPIN (-275 2225) BN 26
J 0
(-287 2233);
DISPLAY 0.680851 (-287 2233);
PAINT GREEN (-287 2233);
FORCEPROP 2 LAST CDS_LIB standard
J 0
(-225 2225);
DISPLAY INVISIBLE (-225 2225);
FORCEPROP 1 LAST BODY_TYPE PLUMBING
J 0
(-225 2275);
DISPLAY 0.872340 (-225 2275);
PAINT GREEN (-225 2275);
DISPLAY INVISIBLE (-225 2275);
FORCEPROP 1 LAST HDL_TAP TRUE
J 0
(100 2100);
DISPLAY 0.872340 (100 2100);
DISPLAY INVISIBLE (100 2100);
FORCEPROP 1 LAST PATH I77
J 0
(-227 2225);
DISPLAY 0.872340 (-227 2225);
PAINT GREEN (-227 2225);
DISPLAY INVISIBLE (-227 2225);
FORCEADD TAP..1
(-225 2175);
FORCEPROP 3 LASTPIN (-275 2175) SIG_NAME M_E_CPU0_SB_DQ<25>
J 0
(-265 2185);
DISPLAY 0.659574 (-265 2185);
PAINT MONO (-265 2185);
DISPLAY INVISIBLE (-265 2185);
FORCEPROP 1 LASTPIN (-275 2175) BN 25
J 0
(-287 2183);
DISPLAY 0.680851 (-287 2183);
PAINT GREEN (-287 2183);
FORCEPROP 2 LAST CDS_LIB standard
J 0
(-225 2175);
DISPLAY INVISIBLE (-225 2175);
FORCEPROP 1 LAST BODY_TYPE PLUMBING
J 0
(-225 2225);
DISPLAY 0.872340 (-225 2225);
PAINT GREEN (-225 2225);
DISPLAY INVISIBLE (-225 2225);
FORCEPROP 1 LAST HDL_TAP TRUE
J 0
(100 2050);
DISPLAY 0.872340 (100 2050);
DISPLAY INVISIBLE (100 2050);
FORCEPROP 1 LAST PATH I78
J 0
(-227 2175);
DISPLAY 0.872340 (-227 2175);
PAINT GREEN (-227 2175);
DISPLAY INVISIBLE (-227 2175);
FORCEADD TAP..1
(-225 2275);
FORCEPROP 3 LASTPIN (-275 2275) SIG_NAME M_E_CPU0_SB_DQ<27>
J 0
(-265 2285);
DISPLAY 0.659574 (-265 2285);
PAINT MONO (-265 2285);
DISPLAY INVISIBLE (-265 2285);
FORCEPROP 1 LASTPIN (-275 2275) BN 27
J 0
(-287 2283);
DISPLAY 0.680851 (-287 2283);
PAINT GREEN (-287 2283);
FORCEPROP 2 LAST CDS_LIB standard
J 0
(-225 2275);
DISPLAY INVISIBLE (-225 2275);
FORCEPROP 1 LAST BODY_TYPE PLUMBING
J 0
(-225 2325);
DISPLAY 0.872340 (-225 2325);
PAINT GREEN (-225 2325);
DISPLAY INVISIBLE (-225 2325);
FORCEPROP 1 LAST HDL_TAP TRUE
J 0
(100 2150);
DISPLAY 0.872340 (100 2150);
DISPLAY INVISIBLE (100 2150);
FORCEPROP 1 LAST PATH I79
J 0
(-227 2275);
DISPLAY 0.872340 (-227 2275);
PAINT GREEN (-227 2275);
DISPLAY INVISIBLE (-227 2275);
FORCEADD OFFPAGE..1
(-2725 1575);
FORCEPROP 2 LAST $XR7 97 
J 0
(-3097 1611);
DISPLAY 0.638298 (-3097 1611);
PAINT MONO (-3097 1611);
FORCEPROP 2 LAST $XR6 96 
J 0
(-3007 1611);
DISPLAY 0.638298 (-3007 1611);
PAINT MONO (-3007 1611);
FORCEPROP 2 LAST $XR5 95 
J 0
(-3187 1539);
DISPLAY 0.638298 (-3187 1539);
PAINT MONO (-3187 1539);
FORCEPROP 2 LAST $XR4 94 
J 0
(-3097 1539);
DISPLAY 0.638298 (-3097 1539);
PAINT MONO (-3097 1539);
FORCEPROP 2 LAST $XR3 93 
J 0
(-3007 1539);
DISPLAY 0.638298 (-3007 1539);
PAINT MONO (-3007 1539);
FORCEPROP 2 LAST $XR2 92 
J 0
(-3187 1575);
DISPLAY 0.638298 (-3187 1575);
PAINT MONO (-3187 1575);
FORCEPROP 2 LAST $XR1 90 
J 0
(-3097 1575);
DISPLAY 0.638298 (-3097 1575);
PAINT MONO (-3097 1575);
FORCEPROP 2 LAST $XR0 229 
J 0
(-3007 1575);
DISPLAY 0.638298 (-3007 1575);
PAINT MONO (-3007 1575);
FORCEPROP 2 LAST CDS_LIB standard
J 0
(-2725 1575);
PAINT MONO (-2725 1575);
DISPLAY INVISIBLE (-2725 1575);
FORCEPROP 1 LAST OFFPAGE TRUE
J 0
(-2400 1450);
DISPLAY 0.872340 (-2400 1450);
DISPLAY INVISIBLE (-2400 1450);
FORCEPROP 1 LAST COMMENT_BODY TRUE
J 0
(-2600 1475);
DISPLAY 0.872340 (-2600 1475);
PAINT GREEN (-2600 1475);
DISPLAY INVISIBLE (-2600 1475);
FORCEPROP 2 LAST PATH I8
J 0
(-2675 1650);
DISPLAY 1.021277 (-2675 1650);
DISPLAY INVISIBLE (-2675 1650);
FORCEADD TAP..1
(-225 2325);
FORCEPROP 3 LASTPIN (-275 2325) SIG_NAME M_E_CPU0_SB_DQ<28>
J 0
(-265 2335);
DISPLAY 0.659574 (-265 2335);
PAINT MONO (-265 2335);
DISPLAY INVISIBLE (-265 2335);
FORCEPROP 1 LASTPIN (-275 2325) BN 28
J 0
(-287 2333);
DISPLAY 0.680851 (-287 2333);
PAINT GREEN (-287 2333);
FORCEPROP 2 LAST CDS_LIB standard
J 0
(-225 2325);
DISPLAY INVISIBLE (-225 2325);
FORCEPROP 1 LAST BODY_TYPE PLUMBING
J 0
(-225 2375);
DISPLAY 0.872340 (-225 2375);
PAINT GREEN (-225 2375);
DISPLAY INVISIBLE (-225 2375);
FORCEPROP 1 LAST HDL_TAP TRUE
J 0
(100 2200);
DISPLAY 0.872340 (100 2200);
DISPLAY INVISIBLE (100 2200);
FORCEPROP 1 LAST PATH I80
J 0
(-227 2325);
DISPLAY 0.872340 (-227 2325);
PAINT GREEN (-227 2325);
DISPLAY INVISIBLE (-227 2325);
FORCEADD TAP..1
(-225 2375);
FORCEPROP 3 LASTPIN (-275 2375) SIG_NAME M_E_CPU0_SB_DQ<29>
J 0
(-265 2385);
DISPLAY 0.659574 (-265 2385);
PAINT MONO (-265 2385);
DISPLAY INVISIBLE (-265 2385);
FORCEPROP 1 LASTPIN (-275 2375) BN 29
J 0
(-287 2383);
DISPLAY 0.680851 (-287 2383);
PAINT GREEN (-287 2383);
FORCEPROP 2 LAST CDS_LIB standard
J 0
(-225 2375);
DISPLAY INVISIBLE (-225 2375);
FORCEPROP 1 LAST BODY_TYPE PLUMBING
J 0
(-225 2425);
DISPLAY 0.872340 (-225 2425);
PAINT GREEN (-225 2425);
DISPLAY INVISIBLE (-225 2425);
FORCEPROP 1 LAST HDL_TAP TRUE
J 0
(100 2250);
DISPLAY 0.872340 (100 2250);
DISPLAY INVISIBLE (100 2250);
FORCEPROP 1 LAST PATH I81
J 0
(-227 2375);
DISPLAY 0.872340 (-227 2375);
PAINT GREEN (-227 2375);
DISPLAY INVISIBLE (-227 2375);
FORCEADD TAP..1
(-225 2425);
FORCEPROP 3 LASTPIN (-275 2425) SIG_NAME M_E_CPU0_SB_DQ<30>
J 0
(-265 2435);
DISPLAY 0.659574 (-265 2435);
PAINT MONO (-265 2435);
DISPLAY INVISIBLE (-265 2435);
FORCEPROP 1 LASTPIN (-275 2425) BN 30
J 0
(-287 2433);
DISPLAY 0.680851 (-287 2433);
PAINT GREEN (-287 2433);
FORCEPROP 2 LAST CDS_LIB standard
J 0
(-225 2425);
DISPLAY INVISIBLE (-225 2425);
FORCEPROP 1 LAST BODY_TYPE PLUMBING
J 0
(-225 2475);
DISPLAY 0.872340 (-225 2475);
PAINT GREEN (-225 2475);
DISPLAY INVISIBLE (-225 2475);
FORCEPROP 1 LAST HDL_TAP TRUE
J 0
(100 2300);
DISPLAY 0.872340 (100 2300);
DISPLAY INVISIBLE (100 2300);
FORCEPROP 1 LAST PATH I82
J 0
(-227 2425);
DISPLAY 0.872340 (-227 2425);
PAINT GREEN (-227 2425);
DISPLAY INVISIBLE (-227 2425);
FORCEADD TAP..1
(-225 2475);
FORCEPROP 3 LASTPIN (-275 2475) SIG_NAME M_E_CPU0_SB_DQ<31>
J 0
(-265 2485);
DISPLAY 0.659574 (-265 2485);
PAINT MONO (-265 2485);
DISPLAY INVISIBLE (-265 2485);
FORCEPROP 1 LASTPIN (-275 2475) BN 31
J 0
(-287 2483);
DISPLAY 0.680851 (-287 2483);
PAINT GREEN (-287 2483);
FORCEPROP 2 LAST CDS_LIB standard
J 0
(-225 2475);
DISPLAY INVISIBLE (-225 2475);
FORCEPROP 1 LAST BODY_TYPE PLUMBING
J 0
(-225 2525);
DISPLAY 0.872340 (-225 2525);
PAINT GREEN (-225 2525);
DISPLAY INVISIBLE (-225 2525);
FORCEPROP 1 LAST HDL_TAP TRUE
J 0
(100 2350);
DISPLAY 0.872340 (100 2350);
DISPLAY INVISIBLE (100 2350);
FORCEPROP 1 LAST PATH I83
J 0
(-227 2475);
DISPLAY 0.872340 (-227 2475);
PAINT GREEN (-227 2475);
DISPLAY INVISIBLE (-227 2475);
FORCEADD TAP..1
(-225 2575);
FORCEPROP 3 LASTPIN (-275 2575) SIG_NAME M_E_CPU0_SA_DQ<0>
J 0
(-265 2585);
DISPLAY 0.659574 (-265 2585);
PAINT MONO (-265 2585);
DISPLAY INVISIBLE (-265 2585);
FORCEPROP 1 LASTPIN (-275 2575) BN 0
J 0
(-287 2583);
DISPLAY 0.680851 (-287 2583);
PAINT GREEN (-287 2583);
FORCEPROP 2 LAST CDS_LIB standard
J 0
(-225 2575);
PAINT MONO (-225 2575);
DISPLAY INVISIBLE (-225 2575);
FORCEPROP 1 LAST BODY_TYPE PLUMBING
J 0
(-225 2625);
DISPLAY 0.872340 (-225 2625);
PAINT GREEN (-225 2625);
DISPLAY INVISIBLE (-225 2625);
FORCEPROP 1 LAST HDL_TAP TRUE
J 0
(100 2450);
DISPLAY 0.872340 (100 2450);
DISPLAY INVISIBLE (100 2450);
FORCEPROP 1 LAST PATH I84
J 0
(-227 2575);
DISPLAY 0.872340 (-227 2575);
PAINT GREEN (-227 2575);
DISPLAY INVISIBLE (-227 2575);
FORCEADD TAP..1
(-225 2675);
FORCEPROP 3 LASTPIN (-275 2675) SIG_NAME M_E_CPU0_SA_DQ<2>
J 0
(-265 2685);
DISPLAY 0.659574 (-265 2685);
PAINT MONO (-265 2685);
DISPLAY INVISIBLE (-265 2685);
FORCEPROP 1 LASTPIN (-275 2675) BN 2
J 0
(-287 2683);
DISPLAY 0.680851 (-287 2683);
PAINT GREEN (-287 2683);
FORCEPROP 2 LAST CDS_LIB standard
J 0
(-225 2675);
PAINT MONO (-225 2675);
DISPLAY INVISIBLE (-225 2675);
FORCEPROP 1 LAST BODY_TYPE PLUMBING
J 0
(-225 2725);
DISPLAY 0.872340 (-225 2725);
PAINT GREEN (-225 2725);
DISPLAY INVISIBLE (-225 2725);
FORCEPROP 1 LAST HDL_TAP TRUE
J 0
(100 2550);
DISPLAY 0.872340 (100 2550);
DISPLAY INVISIBLE (100 2550);
FORCEPROP 1 LAST PATH I85
J 0
(-227 2675);
DISPLAY 0.872340 (-227 2675);
PAINT GREEN (-227 2675);
DISPLAY INVISIBLE (-227 2675);
FORCEADD TAP..1
(-225 2625);
FORCEPROP 3 LASTPIN (-275 2625) SIG_NAME M_E_CPU0_SA_DQ<1>
J 0
(-265 2635);
DISPLAY 0.659574 (-265 2635);
PAINT MONO (-265 2635);
DISPLAY INVISIBLE (-265 2635);
FORCEPROP 1 LASTPIN (-275 2625) BN 1
J 0
(-287 2633);
DISPLAY 0.680851 (-287 2633);
PAINT GREEN (-287 2633);
FORCEPROP 2 LAST CDS_LIB standard
J 0
(-225 2625);
PAINT MONO (-225 2625);
DISPLAY INVISIBLE (-225 2625);
FORCEPROP 1 LAST BODY_TYPE PLUMBING
J 0
(-225 2675);
DISPLAY 0.872340 (-225 2675);
PAINT GREEN (-225 2675);
DISPLAY INVISIBLE (-225 2675);
FORCEPROP 1 LAST HDL_TAP TRUE
J 0
(100 2500);
DISPLAY 0.872340 (100 2500);
DISPLAY INVISIBLE (100 2500);
FORCEPROP 1 LAST PATH I86
J 0
(-227 2625);
DISPLAY 0.872340 (-227 2625);
PAINT GREEN (-227 2625);
DISPLAY INVISIBLE (-227 2625);
FORCEADD TAP..1
(-225 2725);
FORCEPROP 3 LASTPIN (-275 2725) SIG_NAME M_E_CPU0_SA_DQ<3>
J 0
(-265 2735);
DISPLAY 0.659574 (-265 2735);
PAINT MONO (-265 2735);
DISPLAY INVISIBLE (-265 2735);
FORCEPROP 1 LASTPIN (-275 2725) BN 3
J 0
(-287 2733);
DISPLAY 0.680851 (-287 2733);
PAINT GREEN (-287 2733);
FORCEPROP 2 LAST CDS_LIB standard
J 0
(-225 2725);
PAINT MONO (-225 2725);
DISPLAY INVISIBLE (-225 2725);
FORCEPROP 1 LAST BODY_TYPE PLUMBING
J 0
(-225 2775);
DISPLAY 0.872340 (-225 2775);
PAINT GREEN (-225 2775);
DISPLAY INVISIBLE (-225 2775);
FORCEPROP 1 LAST HDL_TAP TRUE
J 0
(100 2600);
DISPLAY 0.872340 (100 2600);
DISPLAY INVISIBLE (100 2600);
FORCEPROP 1 LAST PATH I87
J 0
(-227 2725);
DISPLAY 0.872340 (-227 2725);
PAINT GREEN (-227 2725);
DISPLAY INVISIBLE (-227 2725);
FORCEADD TAP..1
(-225 2775);
FORCEPROP 3 LASTPIN (-275 2775) SIG_NAME M_E_CPU0_SA_DQ<4>
J 0
(-265 2785);
DISPLAY 0.659574 (-265 2785);
PAINT MONO (-265 2785);
DISPLAY INVISIBLE (-265 2785);
FORCEPROP 1 LASTPIN (-275 2775) BN 4
J 0
(-287 2783);
DISPLAY 0.680851 (-287 2783);
PAINT GREEN (-287 2783);
FORCEPROP 2 LAST CDS_LIB standard
J 0
(-225 2775);
PAINT MONO (-225 2775);
DISPLAY INVISIBLE (-225 2775);
FORCEPROP 1 LAST BODY_TYPE PLUMBING
J 0
(-225 2825);
DISPLAY 0.872340 (-225 2825);
PAINT GREEN (-225 2825);
DISPLAY INVISIBLE (-225 2825);
FORCEPROP 1 LAST HDL_TAP TRUE
J 0
(100 2650);
DISPLAY 0.872340 (100 2650);
DISPLAY INVISIBLE (100 2650);
FORCEPROP 1 LAST PATH I88
J 0
(-227 2775);
DISPLAY 0.872340 (-227 2775);
PAINT GREEN (-227 2775);
DISPLAY INVISIBLE (-227 2775);
FORCEADD TAP..1
(-225 2825);
FORCEPROP 3 LASTPIN (-275 2825) SIG_NAME M_E_CPU0_SA_DQ<5>
J 0
(-265 2835);
DISPLAY 0.659574 (-265 2835);
PAINT MONO (-265 2835);
DISPLAY INVISIBLE (-265 2835);
FORCEPROP 1 LASTPIN (-275 2825) BN 5
J 0
(-287 2833);
DISPLAY 0.680851 (-287 2833);
PAINT GREEN (-287 2833);
FORCEPROP 2 LAST CDS_LIB standard
J 0
(-225 2825);
PAINT MONO (-225 2825);
DISPLAY INVISIBLE (-225 2825);
FORCEPROP 1 LAST BODY_TYPE PLUMBING
J 0
(-225 2875);
DISPLAY 0.872340 (-225 2875);
PAINT GREEN (-225 2875);
DISPLAY INVISIBLE (-225 2875);
FORCEPROP 1 LAST HDL_TAP TRUE
J 0
(100 2700);
DISPLAY 0.872340 (100 2700);
DISPLAY INVISIBLE (100 2700);
FORCEPROP 1 LAST PATH I89
J 0
(-227 2825);
DISPLAY 0.872340 (-227 2825);
PAINT GREEN (-227 2825);
DISPLAY INVISIBLE (-227 2825);
FORCEADD OFFPAGE..1
(-2725 1625);
FORCEPROP 2 LAST $XR0 91 
J 0
(-3186 1625);
DISPLAY 0.638298 (-3186 1625);
PAINT MONO (-3186 1625);
FORCEPROP 2 LAST CDS_LIB standard
J 0
(-2725 1625);
PAINT MONO (-2725 1625);
DISPLAY INVISIBLE (-2725 1625);
FORCEPROP 1 LAST OFFPAGE TRUE
J 0
(-2400 1500);
DISPLAY 0.872340 (-2400 1500);
DISPLAY INVISIBLE (-2400 1500);
FORCEPROP 1 LAST COMMENT_BODY TRUE
J 0
(-2600 1525);
DISPLAY 0.872340 (-2600 1525);
PAINT GREEN (-2600 1525);
DISPLAY INVISIBLE (-2600 1525);
FORCEPROP 2 LAST PATH I9
J 0
(-2675 1700);
DISPLAY 1.021277 (-2675 1700);
DISPLAY INVISIBLE (-2675 1700);
FORCEADD TAP..1
(-225 2925);
FORCEPROP 3 LASTPIN (-275 2925) SIG_NAME M_E_CPU0_SA_DQ<7>
J 0
(-265 2935);
DISPLAY 0.659574 (-265 2935);
PAINT MONO (-265 2935);
DISPLAY INVISIBLE (-265 2935);
FORCEPROP 1 LASTPIN (-275 2925) BN 7
J 0
(-287 2933);
DISPLAY 0.680851 (-287 2933);
PAINT GREEN (-287 2933);
FORCEPROP 2 LAST CDS_LIB standard
J 0
(-225 2925);
PAINT MONO (-225 2925);
DISPLAY INVISIBLE (-225 2925);
FORCEPROP 1 LAST BODY_TYPE PLUMBING
J 0
(-225 2975);
DISPLAY 0.872340 (-225 2975);
PAINT GREEN (-225 2975);
DISPLAY INVISIBLE (-225 2975);
FORCEPROP 1 LAST HDL_TAP TRUE
J 0
(100 2800);
DISPLAY 0.872340 (100 2800);
DISPLAY INVISIBLE (100 2800);
FORCEPROP 1 LAST PATH I90
J 0
(-227 2925);
DISPLAY 0.872340 (-227 2925);
PAINT GREEN (-227 2925);
DISPLAY INVISIBLE (-227 2925);
FORCEADD TAP..1
(-225 2975);
FORCEPROP 3 LASTPIN (-275 2975) SIG_NAME M_E_CPU0_SA_DQ<8>
J 0
(-265 2985);
DISPLAY 0.659574 (-265 2985);
PAINT MONO (-265 2985);
DISPLAY INVISIBLE (-265 2985);
FORCEPROP 1 LASTPIN (-275 2975) BN 8
J 0
(-287 2983);
DISPLAY 0.680851 (-287 2983);
PAINT GREEN (-287 2983);
FORCEPROP 2 LAST CDS_LIB standard
J 0
(-225 2975);
PAINT MONO (-225 2975);
DISPLAY INVISIBLE (-225 2975);
FORCEPROP 1 LAST BODY_TYPE PLUMBING
J 0
(-225 3025);
DISPLAY 0.872340 (-225 3025);
PAINT GREEN (-225 3025);
DISPLAY INVISIBLE (-225 3025);
FORCEPROP 1 LAST HDL_TAP TRUE
J 0
(100 2850);
DISPLAY 0.872340 (100 2850);
DISPLAY INVISIBLE (100 2850);
FORCEPROP 1 LAST PATH I91
J 0
(-227 2975);
DISPLAY 0.872340 (-227 2975);
PAINT GREEN (-227 2975);
DISPLAY INVISIBLE (-227 2975);
FORCEADD TAP..1
(-225 2875);
FORCEPROP 3 LASTPIN (-275 2875) SIG_NAME M_E_CPU0_SA_DQ<6>
J 0
(-265 2885);
DISPLAY 0.659574 (-265 2885);
PAINT MONO (-265 2885);
DISPLAY INVISIBLE (-265 2885);
FORCEPROP 1 LASTPIN (-275 2875) BN 6
J 0
(-287 2883);
DISPLAY 0.680851 (-287 2883);
PAINT GREEN (-287 2883);
FORCEPROP 2 LAST CDS_LIB standard
J 0
(-225 2875);
PAINT MONO (-225 2875);
DISPLAY INVISIBLE (-225 2875);
FORCEPROP 1 LAST BODY_TYPE PLUMBING
J 0
(-225 2925);
DISPLAY 0.872340 (-225 2925);
PAINT GREEN (-225 2925);
DISPLAY INVISIBLE (-225 2925);
FORCEPROP 1 LAST HDL_TAP TRUE
J 0
(100 2750);
DISPLAY 0.872340 (100 2750);
DISPLAY INVISIBLE (100 2750);
FORCEPROP 1 LAST PATH I92
J 0
(-227 2875);
DISPLAY 0.872340 (-227 2875);
PAINT GREEN (-227 2875);
DISPLAY INVISIBLE (-227 2875);
FORCEADD TAP..1
(-225 3025);
FORCEPROP 3 LASTPIN (-275 3025) SIG_NAME M_E_CPU0_SA_DQ<9>
J 0
(-265 3035);
DISPLAY 0.659574 (-265 3035);
PAINT MONO (-265 3035);
DISPLAY INVISIBLE (-265 3035);
FORCEPROP 1 LASTPIN (-275 3025) BN 9
J 0
(-287 3033);
DISPLAY 0.680851 (-287 3033);
PAINT GREEN (-287 3033);
FORCEPROP 2 LAST CDS_LIB standard
J 0
(-225 3025);
PAINT MONO (-225 3025);
DISPLAY INVISIBLE (-225 3025);
FORCEPROP 1 LAST BODY_TYPE PLUMBING
J 0
(-225 3075);
DISPLAY 0.872340 (-225 3075);
PAINT GREEN (-225 3075);
DISPLAY INVISIBLE (-225 3075);
FORCEPROP 1 LAST HDL_TAP TRUE
J 0
(100 2900);
DISPLAY 0.872340 (100 2900);
DISPLAY INVISIBLE (100 2900);
FORCEPROP 1 LAST PATH I93
J 0
(-227 3025);
DISPLAY 0.872340 (-227 3025);
PAINT GREEN (-227 3025);
DISPLAY INVISIBLE (-227 3025);
FORCEADD TAP..1
(-225 3075);
FORCEPROP 3 LASTPIN (-275 3075) SIG_NAME M_E_CPU0_SA_DQ<10>
J 0
(-265 3085);
DISPLAY 0.659574 (-265 3085);
PAINT MONO (-265 3085);
DISPLAY INVISIBLE (-265 3085);
FORCEPROP 1 LASTPIN (-275 3075) BN 10
J 0
(-287 3083);
DISPLAY 0.680851 (-287 3083);
PAINT GREEN (-287 3083);
FORCEPROP 2 LAST CDS_LIB standard
J 0
(-225 3075);
PAINT MONO (-225 3075);
DISPLAY INVISIBLE (-225 3075);
FORCEPROP 1 LAST BODY_TYPE PLUMBING
J 0
(-225 3125);
DISPLAY 0.872340 (-225 3125);
PAINT GREEN (-225 3125);
DISPLAY INVISIBLE (-225 3125);
FORCEPROP 1 LAST HDL_TAP TRUE
J 0
(100 2950);
DISPLAY 0.872340 (100 2950);
DISPLAY INVISIBLE (100 2950);
FORCEPROP 1 LAST PATH I94
J 0
(-227 3075);
DISPLAY 0.872340 (-227 3075);
PAINT GREEN (-227 3075);
DISPLAY INVISIBLE (-227 3075);
FORCEADD TAP..1
(-225 3125);
FORCEPROP 3 LASTPIN (-275 3125) SIG_NAME M_E_CPU0_SA_DQ<11>
J 0
(-265 3135);
DISPLAY 0.659574 (-265 3135);
PAINT MONO (-265 3135);
DISPLAY INVISIBLE (-265 3135);
FORCEPROP 1 LASTPIN (-275 3125) BN 11
J 0
(-287 3133);
DISPLAY 0.680851 (-287 3133);
PAINT GREEN (-287 3133);
FORCEPROP 2 LAST CDS_LIB standard
J 0
(-225 3125);
PAINT MONO (-225 3125);
DISPLAY INVISIBLE (-225 3125);
FORCEPROP 1 LAST BODY_TYPE PLUMBING
J 0
(-225 3175);
DISPLAY 0.872340 (-225 3175);
PAINT GREEN (-225 3175);
DISPLAY INVISIBLE (-225 3175);
FORCEPROP 1 LAST HDL_TAP TRUE
J 0
(100 3000);
DISPLAY 0.872340 (100 3000);
DISPLAY INVISIBLE (100 3000);
FORCEPROP 1 LAST PATH I95
J 0
(-227 3125);
DISPLAY 0.872340 (-227 3125);
PAINT GREEN (-227 3125);
DISPLAY INVISIBLE (-227 3125);
FORCEADD TAP..1
(-225 3175);
FORCEPROP 3 LASTPIN (-275 3175) SIG_NAME M_E_CPU0_SA_DQ<12>
J 0
(-265 3185);
DISPLAY 0.659574 (-265 3185);
PAINT MONO (-265 3185);
DISPLAY INVISIBLE (-265 3185);
FORCEPROP 1 LASTPIN (-275 3175) BN 12
J 0
(-287 3183);
DISPLAY 0.680851 (-287 3183);
PAINT GREEN (-287 3183);
FORCEPROP 2 LAST CDS_LIB standard
J 0
(-225 3175);
PAINT MONO (-225 3175);
DISPLAY INVISIBLE (-225 3175);
FORCEPROP 1 LAST BODY_TYPE PLUMBING
J 0
(-225 3225);
DISPLAY 0.872340 (-225 3225);
PAINT GREEN (-225 3225);
DISPLAY INVISIBLE (-225 3225);
FORCEPROP 1 LAST HDL_TAP TRUE
J 0
(100 3050);
DISPLAY 0.872340 (100 3050);
DISPLAY INVISIBLE (100 3050);
FORCEPROP 1 LAST PATH I96
J 0
(-227 3175);
DISPLAY 0.872340 (-227 3175);
PAINT GREEN (-227 3175);
DISPLAY INVISIBLE (-227 3175);
FORCEADD TAP..1
(-225 3225);
FORCEPROP 3 LASTPIN (-275 3225) SIG_NAME M_E_CPU0_SA_DQ<13>
J 0
(-265 3235);
DISPLAY 0.659574 (-265 3235);
PAINT MONO (-265 3235);
DISPLAY INVISIBLE (-265 3235);
FORCEPROP 1 LASTPIN (-275 3225) BN 13
J 0
(-287 3233);
DISPLAY 0.680851 (-287 3233);
PAINT GREEN (-287 3233);
FORCEPROP 2 LAST CDS_LIB standard
J 0
(-225 3225);
PAINT MONO (-225 3225);
DISPLAY INVISIBLE (-225 3225);
FORCEPROP 1 LAST BODY_TYPE PLUMBING
J 0
(-225 3275);
DISPLAY 0.872340 (-225 3275);
PAINT GREEN (-225 3275);
DISPLAY INVISIBLE (-225 3275);
FORCEPROP 1 LAST HDL_TAP TRUE
J 0
(100 3100);
DISPLAY 0.872340 (100 3100);
DISPLAY INVISIBLE (100 3100);
FORCEPROP 1 LAST PATH I97
J 0
(-227 3225);
DISPLAY 0.872340 (-227 3225);
PAINT GREEN (-227 3225);
DISPLAY INVISIBLE (-227 3225);
FORCEADD TAP..1
(-225 3275);
FORCEPROP 3 LASTPIN (-275 3275) SIG_NAME M_E_CPU0_SA_DQ<14>
J 0
(-265 3285);
DISPLAY 0.659574 (-265 3285);
PAINT MONO (-265 3285);
DISPLAY INVISIBLE (-265 3285);
FORCEPROP 1 LASTPIN (-275 3275) BN 14
J 0
(-287 3283);
DISPLAY 0.680851 (-287 3283);
PAINT GREEN (-287 3283);
FORCEPROP 2 LAST CDS_LIB standard
J 0
(-225 3275);
PAINT MONO (-225 3275);
DISPLAY INVISIBLE (-225 3275);
FORCEPROP 1 LAST BODY_TYPE PLUMBING
J 0
(-225 3325);
DISPLAY 0.872340 (-225 3325);
PAINT GREEN (-225 3325);
DISPLAY INVISIBLE (-225 3325);
FORCEPROP 1 LAST HDL_TAP TRUE
J 0
(100 3150);
DISPLAY 0.872340 (100 3150);
DISPLAY INVISIBLE (100 3150);
FORCEPROP 1 LAST PATH I98
J 0
(-227 3275);
DISPLAY 0.872340 (-227 3275);
PAINT GREEN (-227 3275);
DISPLAY INVISIBLE (-227 3275);
FORCEADD TAP..1
(-225 3375);
FORCEPROP 3 LASTPIN (-275 3375) SIG_NAME M_E_CPU0_SA_DQ<16>
J 0
(-265 3385);
DISPLAY 0.659574 (-265 3385);
PAINT MONO (-265 3385);
DISPLAY INVISIBLE (-265 3385);
FORCEPROP 1 LASTPIN (-275 3375) BN 16
J 0
(-287 3383);
DISPLAY 0.680851 (-287 3383);
PAINT GREEN (-287 3383);
FORCEPROP 2 LAST CDS_LIB standard
J 0
(-225 3375);
PAINT MONO (-225 3375);
DISPLAY INVISIBLE (-225 3375);
FORCEPROP 1 LAST BODY_TYPE PLUMBING
J 0
(-225 3425);
DISPLAY 0.872340 (-225 3425);
PAINT GREEN (-225 3425);
DISPLAY INVISIBLE (-225 3425);
FORCEPROP 1 LAST HDL_TAP TRUE
J 0
(100 3250);
DISPLAY 0.872340 (100 3250);
DISPLAY INVISIBLE (100 3250);
FORCEPROP 1 LAST PATH I99
J 0
(-227 3375);
DISPLAY 0.872340 (-227 3375);
PAINT GREEN (-227 3375);
DISPLAY INVISIBLE (-227 3375);
FORCEADD CAD_NOTE..1
(1625 -325);
FORCEPROP 0 LAST S1 PLACE THE BYPASS CAPS CLOSE TO DIMM
J 0
(1500 -450);
DISPLAY 1.021277 (1500 -450);
PAINT WHITE (1500 -450);
FORCEPROP 2 LAST CDS_LIB logical_power
J 0
(1625 -325);
PAINT MONO (1625 -325);
DISPLAY INVISIBLE (1625 -325);
FORCEPROP 1 LAST COMMENT_BODY TRUE
J 0
(1650 -225);
DISPLAY 0.978723 (1650 -225);
DISPLAY INVISIBLE (1650 -225);
FORCEADD QUANTA_TITLE_BLOCK_C..1
(6100 -1625);
FORCEPROP 0 LAST CDS_CON_LAST_MODIFIED Fri Aug 25 14:01:10 2023
J 0
(4215 -1610);
PAINT MONO (4215 -1610);
DISPLAY INVISIBLE (4215 -1610);
FORCEPROP 1 LAST CUSTOM_TXT_CDS <CON_LAST_MODIFIED>
J 0
(4215 -1610);
DISPLAY 0.978723 (4215 -1610);
FORCEPROP 2 LAST CUSTOM_TXT_CDS <XR_PAGE_TITLE>
J 0
(-1790 3625);
DISPLAY 0.638298 (-1790 3625);
PAINT PINK (-1790 3625);
DISPLAY INVISIBLE (-1790 3625);
FORCEPROP 2 LAST CUSTOM_TXT_CDS <Q_NUMBER>
J 0
(4697 -1522);
DISPLAY 1.212766 (4697 -1522);
FORCEPROP 1 LAST CUSTOM_TXT_CDS <NAME_2>
J 0
(2925 -1575);
FORCEPROP 1 LAST CUSTOM_TXT_CDS <NAME_1>
J 0
(2925 -1450);
FORCEPROP 1 LAST CUSTOM_TXT_CDS <Q_PROJ>
J 0
(3718 -1523);
DISPLAY 1.212766 (3718 -1523);
FORCEPROP 1 LAST CUSTOM_TXT_CDS <Q_REV>
J 0
(5916 -1522);
DISPLAY 1.212766 (5916 -1522);
FORCEPROP 1 LAST CUSTOM_TXT_CDS <CON_PAGE_NUM> OF <CON_TOTAL_PAGES>
J 0
(5654 -1607);
DISPLAY 0.978723 (5654 -1607);
FORCEPROP 1 LAST Q_TITLE DDR5 - CPU0 CHE DIMM2(BLACK)
J 0
(-3266 -1599);
DISPLAY 2.446809 (-3266 -1599);
PAINT GREEN (-3266 -1599);
FORCEPROP 1 LAST Q_DEPT 
J 1
(2337 -1576);
DISPLAY 1.957447 (2337 -1576);
PAINT GREEN (2337 -1576);
FORCEPROP 1 LAST COMMENT_BODY TRUE
J 0
(6112 -1638);
DISPLAY 0.978723 (6112 -1638);
PAINT GREEN (6112 -1638);
DISPLAY INVISIBLE (6112 -1638);
FORCEPROP 2 LAST CDS_XR_PAGE_TITLE CR-91 : @S9S_MB_2U_LIB.S9S_MB_2U(SCH_1):PAGE91
J 0
(-1790 3625);
DISPLAY 0.638298 (-1790 3625);
PAINT PINK (-1790 3625);
DISPLAY INVISIBLE (-1790 3625);
FORCEPROP 2 LAST PAGE_BORDER TRUE
J 0
(-1790 3625);
DISPLAY 0.638298 (-1790 3625);
PAINT PINK (-1790 3625);
DISPLAY INVISIBLE (-1790 3625);
FORCEPROP 1 LAST CDS_LMAN_SYM_OUTLINE -9475,6775,100,-125
J 0
(6100 -1625);
DISPLAY 0.468085 (6100 -1625);
PAINT GREEN (6100 -1625);
DISPLAY INVISIBLE (6100 -1625);
FORCEPROP 2 LAST CDS_LIB pure_quanta
J 0
(6100 -1625);
PAINT MONO (6100 -1625);
DISPLAY INVISIBLE (6100 -1625);
WIRE 17 -1 (-175 4150)(550 4150);
FORCEPROP 2 LAST SIG_NAME M_E_CPU0_SA_DQ<31:0>
J 0
(-110 4160);
DISPLAY 0.680851 (-110 4160);
PAINT WHITE (-110 4160);
WIRE 17 -1 (-2750 2750)(-1925 2750);
FORCEPROP 2 LAST SIG_NAME M_E_CPU0_SA_CB<7:0>
J 0
(-2660 2760);
DISPLAY 0.680851 (-2660 2760);
PAINT WHITE (-2660 2760);
WIRE 17 -1 (-1925 2600)(-1925 2650);
WIRE 17 -1 (-1925 2550)(-1925 2600);
WIRE 17 -1 (-1925 2650)(-1925 2700);
WIRE 17 -1 (-1925 2700)(-1925 2750);
WIRE 17 -1 (-1925 2500)(-1925 2550);
WIRE 17 -1 (-1925 2450)(-1925 2500);
WIRE 17 -1 (-1925 2400)(-1925 2450);
WIRE 17 -1 (-2750 2300)(-1925 2300);
FORCEPROP 2 LAST SIG_NAME M_E_CPU0_SB_CB<7:0>
J 0
(-2660 2310);
DISPLAY 0.680851 (-2660 2310);
PAINT WHITE (-2660 2310);
WIRE 17 -1 (-1925 3850)(-1925 3900);
WIRE 17 -1 (-1925 3900)(-1925 3950);
WIRE 17 -1 (-1925 3950)(-1925 4000);
WIRE 17 -1 (-1925 4000)(-1925 4050);
WIRE 17 -1 (-1925 4050)(-1925 4100);
WIRE 17 -1 (-1925 4100)(-1925 4150);
WIRE 17 -1 (-2750 4150)(-1925 4150);
FORCEPROP 2 LAST SIG_NAME M_E_CPU0_SA_CA<6:0>
J 0
(-2660 4160);
DISPLAY 0.680851 (-2660 4160);
PAINT WHITE (-2660 4160);
WIRE 17 -1 (-1925 3450)(-1925 3500);
WIRE 17 -1 (-1925 3500)(-1925 3550);
WIRE 17 -1 (-1925 3550)(-1925 3600);
WIRE 17 -1 (-1925 3600)(-1925 3650);
WIRE 17 -1 (-1925 3650)(-1925 3700);
WIRE 17 -1 (-1925 3700)(-1925 3750);
WIRE 17 -1 (-2750 3750)(-1925 3750);
FORCEPROP 2 LAST SIG_NAME M_E_CPU0_SB_CA<6:0>
J 0
(-2660 3760);
DISPLAY 0.680851 (-2660 3760);
PAINT WHITE (-2660 3760);
WIRE 17 -1 (-1925 2250)(-1925 2300);
WIRE 17 -1 (-1925 2200)(-1925 2250);
WIRE 17 -1 (-1925 2150)(-1925 2200);
WIRE 17 -1 (-1925 2100)(-1925 2150);
WIRE 17 -1 (-1925 2050)(-1925 2100);
WIRE 17 -1 (-1925 2000)(-1925 2050);
WIRE 17 -1 (-1925 1950)(-1925 2000);
WIRE 17 -1 (-175 4100)(-175 4150);
WIRE 17 -1 (-175 4050)(-175 4100);
WIRE 17 -1 (-175 4000)(-175 4050);
WIRE 17 -1 (-175 3950)(-175 4000);
WIRE 17 -1 (-175 3900)(-175 3950);
WIRE 17 -1 (-175 3850)(-175 3900);
WIRE 17 -1 (-175 3800)(-175 3850);
WIRE 17 -1 (-175 3750)(-175 3800);
WIRE 17 -1 (-175 3700)(-175 3750);
WIRE 17 -1 (-175 3650)(-175 3700);
WIRE 17 -1 (-175 3600)(-175 3650);
WIRE 17 -1 (-175 3550)(-175 3600);
WIRE 17 -1 (-175 3500)(-175 3550);
WIRE 17 -1 (-175 3450)(-175 3500);
WIRE 17 -1 (-175 3400)(-175 3450);
WIRE 17 -1 (-175 3350)(-175 3400);
WIRE 17 -1 (-175 3300)(-175 3350);
WIRE 17 -1 (-175 3250)(-175 3300);
WIRE 17 -1 (-175 3200)(-175 3250);
WIRE 17 -1 (-175 3150)(-175 3200);
WIRE 17 -1 (-175 3100)(-175 3150);
WIRE 17 -1 (-175 3050)(-175 3100);
WIRE 17 -1 (-175 3000)(-175 3050);
WIRE 17 -1 (-175 2950)(-175 3000);
WIRE 17 -1 (-175 2900)(-175 2950);
WIRE 17 -1 (-175 2850)(-175 2900);
WIRE 17 -1 (-175 2800)(-175 2850);
WIRE 17 -1 (-175 2750)(-175 2800);
WIRE 17 -1 (-175 2700)(-175 2750);
WIRE 17 -1 (-175 2650)(-175 2700);
WIRE 17 -1 (-175 2600)(-175 2650);
WIRE 17 -1 (-175 2500)(550 2500);
FORCEPROP 2 LAST SIG_NAME M_E_CPU0_SB_DQ<31:0>
J 0
(-110 2510);
DISPLAY 0.680851 (-110 2510);
PAINT WHITE (-110 2510);
WIRE 17 -1 (-175 2400)(-175 2450);
WIRE 17 -1 (-175 2350)(-175 2400);
WIRE 17 -1 (-175 2450)(-175 2500);
WIRE 17 -1 (-175 2300)(-175 2350);
WIRE 17 -1 (-175 2250)(-175 2300);
WIRE 17 -1 (-175 2200)(-175 2250);
WIRE 17 -1 (-175 2150)(-175 2200);
WIRE 17 -1 (-175 2100)(-175 2150);
WIRE 17 -1 (-175 2050)(-175 2100);
WIRE 17 -1 (-175 2000)(-175 2050);
WIRE 17 -1 (-175 1950)(-175 2000);
WIRE 17 -1 (-175 1900)(-175 1950);
WIRE 17 -1 (-175 1850)(-175 1900);
WIRE 17 -1 (-175 1800)(-175 1850);
WIRE 17 -1 (-175 1750)(-175 1800);
WIRE 17 -1 (-175 1700)(-175 1750);
WIRE 17 -1 (-175 1650)(-175 1700);
WIRE 17 -1 (-175 1600)(-175 1650);
WIRE 17 -1 (-175 1550)(-175 1600);
WIRE 17 -1 (-175 1500)(-175 1550);
WIRE 17 -1 (-175 1450)(-175 1500);
WIRE 17 -1 (-175 1400)(-175 1450);
WIRE 17 -1 (-175 1350)(-175 1400);
WIRE 17 -1 (-175 1300)(-175 1350);
WIRE 17 -1 (-175 1250)(-175 1300);
WIRE 17 -1 (-175 1200)(-175 1250);
WIRE 17 -1 (-175 1150)(-175 1200);
WIRE 17 -1 (-175 1100)(-175 1150);
WIRE 17 -1 (-175 1050)(-175 1100);
WIRE 17 -1 (-175 1000)(-175 1050);
WIRE 17 -1 (-175 950)(-175 1000);
WIRE 17 -1 (2575 2200)(2575 2300);
WIRE 17 -1 (2575 2300)(2575 2400);
WIRE 17 -1 (2575 2400)(2575 2500);
WIRE 17 -1 (2575 2600)(2575 2500);
WIRE 17 -1 (2575 2600)(2575 2700);
WIRE 17 -1 (2575 2700)(2575 2800);
WIRE 17 -1 (2575 2800)(2575 2900);
WIRE 17 -1 (2575 2900)(2575 3000);
WIRE 17 -1 (2575 3000)(2575 3100);
WIRE 17 -1 (2575 3100)(3600 3100);
FORCEPROP 2 LAST SIG_NAME M_E_CPU0_SB_DQS_DP<9:0>
J 0
(2815 3110);
DISPLAY 0.680851 (2815 3110);
PAINT WHITE (2815 3110);
WIRE 17 -1 (2575 3250)(2575 3350);
WIRE 17 -1 (2575 3350)(2575 3450);
WIRE 17 -1 (2575 3450)(2575 3550);
WIRE 17 -1 (2575 3650)(2575 3550);
WIRE 17 -1 (2575 3650)(2575 3750);
WIRE 17 -1 (2575 3750)(2575 3850);
WIRE 17 -1 (2575 3850)(2575 3950);
WIRE 17 -1 (2575 3950)(2575 4050);
WIRE 17 -1 (2575 4050)(2575 4150);
WIRE 17 -1 (2575 4150)(3600 4150);
FORCEPROP 2 LAST SIG_NAME M_E_CPU0_SA_DQS_DP<9:0>
J 0
(2815 4160);
DISPLAY 0.680851 (2815 4160);
PAINT WHITE (2815 4160);
WIRE 17 -1 (2750 2150)(2750 2250);
WIRE 17 -1 (2750 2250)(2750 2350);
WIRE 17 -1 (2750 2350)(2750 2450);
WIRE 17 -1 (2750 2550)(2750 2450);
WIRE 17 -1 (2750 2550)(2750 2650);
WIRE 17 -1 (2750 2650)(2750 2750);
WIRE 17 -1 (2750 2750)(2750 2850);
WIRE 17 -1 (2750 2850)(2750 2950);
WIRE 17 -1 (2750 2950)(2750 3050);
WIRE 17 -1 (2750 3050)(3600 3050);
FORCEPROP 2 LAST SIG_NAME M_E_CPU0_SB_DQS_DN<9:0>
J 0
(2815 3060);
DISPLAY 0.680851 (2815 3060);
PAINT WHITE (2815 3060);
WIRE 17 -1 (2750 3200)(2750 3300);
WIRE 17 -1 (2750 3300)(2750 3400);
WIRE 17 -1 (2750 3400)(2750 3500);
WIRE 17 -1 (2750 3600)(2750 3500);
WIRE 17 -1 (2750 3600)(2750 3700);
WIRE 17 -1 (2750 3700)(2750 3800);
WIRE 17 -1 (2750 3800)(2750 3900);
WIRE 17 -1 (2750 3900)(2750 4000);
WIRE 17 -1 (2750 4000)(2750 4100);
WIRE 17 -1 (2750 4100)(3600 4100);
FORCEPROP 2 LAST SIG_NAME M_E_CPU0_SA_DQS_DN<9:0>
J 0
(2815 4110);
DISPLAY 0.680851 (2815 4110);
PAINT WHITE (2815 4110);
WIRE 16 -1 (1500 350)(1500 525);
WIRE 16 -1 (-2700 1950)(-2700 1675);
WIRE 16 -1 (4200 4625)(4200 4125);
WIRE 16 -1 (2500 525)(2500 475);
WIRE 16 -1 (5900 775)(5900 475);
WIRE 16 -1 (5900 825)(5900 775);
WIRE 16 -1 (5650 775)(5900 775);
WIRE 16 -1 (4200 475)(4200 875);
WIRE 16 -1 (3125 -75)(3125 0);
WIRE 16 -1 (1500 150)(1500 -75);
WIRE 16 -1 (-1650 -200)(-1650 -125);
WIRE 16 3135 (1150 750)(1150 -550);
WIRE 16 3135 (3750 750)(1150 750);
WIRE 16 3135 (1150 -550)(3750 -550);
WIRE 16 3135 (3750 -550)(3750 750);
WIRE 16 -1 (-1650 1525)(-3125 1525);
FORCEPROP 2 LAST SIG_NAME I3C_SPD_DDREFGH_CPU0_LVC1_SCL_R2
J 0
(-2710 1535);
DISPLAY 0.680851 (-2710 1535);
PAINT WHITE (-2710 1535);
WIRE 16 -1 (-3125 1400)(-3125 1525);
WIRE 16 -1 (-3125 1400)(-2925 1400);
WIRE 16 -1 (-2700 1675)(-1650 1675);
WIRE 16 -1 (-1650 1625)(-2675 1625);
FORCEPROP 2 LAST SIG_NAME PD_CHE_CPU0_DIMM2_SAA
J 0
(-2685 1635);
DISPLAY 0.680851 (-2685 1635);
PAINT WHITE (-2685 1635);
WIRE 16 -1 (-1650 1575)(-2675 1575);
FORCEPROP 2 LAST SIG_NAME I3C_SPD_DDREFGH_CPU0_LVC1_SDA
J 0
(-2685 1585);
DISPLAY 0.680851 (-2685 1585);
PAINT WHITE (-2685 1585);
WIRE 16 -1 (-1650 1775)(-2750 1775);
FORCEPROP 2 LAST SIG_NAME M_E_CPU0_ALERT_N
J 0
(-2662 1784);
DISPLAY 0.680851 (-2662 1784);
PAINT WHITE (-2662 1784);
WIRE 16 -1 (-2025 1825)(-1650 1825);
WIRE 16 -1 (-2025 1875)(-2750 1875);
FORCEPROP 2 LAST SIG_NAME RST_M_EF_CPU0_FPGA_N
J 0
(-2662 1884);
DISPLAY 0.680851 (-2662 1884);
PAINT WHITE (-2662 1884);
WIRE 16 -1 (-2025 1875)(-2025 1825);
WIRE 16 -1 (-2725 1400)(-1550 1400);
FORCEPROP 2 LAST SIG_NAME I3C_SPD_DDREFGH_CPU0_LVC1_SCL
J 0
(-2560 1410);
DISPLAY 0.680851 (-2560 1410);
PAINT WHITE (-2560 1410);
WIRE 16 -1 (-1550 1400)(-1550 1350);
WIRE 16 -1 (-1550 1350)(-1575 1350);
WIRE 16 -1 (-1650 1075)(-2750 1075);
FORCEPROP 2 LAST SIG_NAME TP_CHE_CPU0_DIMM2_FRU_4
J 0
(-2662 1084);
DISPLAY 0.680851 (-2662 1084);
PAINT WHITE (-2662 1084);
WIRE 16 -1 (-1650 1125)(-2750 1125);
FORCEPROP 2 LAST SIG_NAME TP_CHE_CPU0_DIMM2_FRU_5
J 0
(-2662 1134);
DISPLAY 0.680851 (-2662 1134);
PAINT WHITE (-2662 1134);
WIRE 16 -1 (-1650 1175)(-2750 1175);
FORCEPROP 2 LAST SIG_NAME TP_CHE_CPU0_DIMM2_FRU_6
J 0
(-2662 1184);
DISPLAY 0.680851 (-2662 1184);
PAINT WHITE (-2662 1184);
WIRE 16 -1 (2375 2525)(2650 2525);
WIRE 16 -1 (2375 4075)(2650 4075);
WIRE 16 -1 (2375 3975)(2650 3975);
WIRE 16 -1 (2375 3875)(2650 3875);
WIRE 16 -1 (2375 3775)(2650 3775);
WIRE 16 -1 (2375 3675)(2650 3675);
WIRE 16 -1 (2375 3475)(2650 3475);
WIRE 16 -1 (2375 3575)(2650 3575);
WIRE 16 -1 (2375 3375)(2650 3375);
WIRE 16 -1 (2375 3275)(2650 3275);
WIRE 16 -1 (2375 3175)(2650 3175);
WIRE 16 -1 (2375 3025)(2650 3025);
WIRE 16 -1 (2375 2825)(2650 2825);
WIRE 16 -1 (2375 2925)(2650 2925);
WIRE 16 -1 (2375 2725)(2650 2725);
WIRE 16 -1 (2375 2625)(2650 2625);
WIRE 16 -1 (2375 2325)(2650 2325);
WIRE 16 -1 (2375 2425)(2650 2425);
WIRE 16 -1 (2375 2225)(2650 2225);
WIRE 16 -1 (2375 2125)(2650 2125);
WIRE 16 -1 (2375 4125)(2475 4125);
WIRE 16 -1 (2375 4025)(2475 4025);
WIRE 16 -1 (2375 3925)(2475 3925);
WIRE 16 -1 (2375 3825)(2475 3825);
WIRE 16 -1 (2375 3725)(2475 3725);
WIRE 16 -1 (2375 3625)(2475 3625);
WIRE 16 -1 (2375 3525)(2475 3525);
WIRE 16 -1 (2375 3425)(2475 3425);
WIRE 16 -1 (2375 3325)(2475 3325);
WIRE 16 -1 (2375 3225)(2475 3225);
WIRE 16 -1 (2375 3075)(2475 3075);
WIRE 16 -1 (2375 2975)(2475 2975);
WIRE 16 -1 (2375 2875)(2475 2875);
WIRE 16 -1 (2375 2775)(2475 2775);
WIRE 16 -1 (2375 2675)(2475 2675);
WIRE 16 -1 (2375 2575)(2475 2575);
WIRE 16 -1 (2375 2475)(2475 2475);
WIRE 16 -1 (2375 2375)(2475 2375);
WIRE 16 -1 (2375 2275)(2475 2275);
WIRE 16 -1 (2375 2175)(2475 2175);
WIRE 16 -1 (-1650 1275)(-2750 1275);
FORCEPROP 2 LAST SIG_NAME PWRGD_CHE_CPU0_DIMM2
J 0
(-2662 1284);
DISPLAY 0.680851 (-2662 1284);
PAINT WHITE (-2662 1284);
WIRE 16 -1 (-450 2025)(-275 2025);
WIRE 16 -1 (-1825 2375)(-1650 2375);
WIRE 16 -1 (4450 4125)(4200 4125);
WIRE 16 -1 (4200 4075)(4450 4075);
WIRE 16 -1 (4200 4125)(4200 4075);
WIRE 16 -1 (4200 4075)(4200 4025);
WIRE 16 -1 (4450 4025)(4200 4025);
WIRE 16 -1 (-450 3825)(-275 3825);
WIRE 16 -1 (-450 2775)(-275 2775);
WIRE 16 -1 (4200 875)(4450 875);
WIRE 16 -1 (4200 875)(4200 925);
WIRE 16 -1 (4200 925)(4450 925);
WIRE 16 -1 (4200 925)(4200 975);
WIRE 16 -1 (4200 975)(4450 975);
WIRE 16 -1 (4200 975)(4200 1025);
WIRE 16 -1 (4200 1025)(4450 1025);
WIRE 16 -1 (4200 1025)(4200 1075);
WIRE 16 -1 (4200 1075)(4450 1075);
WIRE 16 -1 (4200 1075)(4200 1125);
WIRE 16 -1 (4200 1125)(4450 1125);
WIRE 16 -1 (4200 1125)(4200 1175);
WIRE 16 -1 (4200 1175)(4450 1175);
WIRE 16 -1 (4200 1175)(4200 1225);
WIRE 16 -1 (4200 1225)(4450 1225);
WIRE 16 -1 (4200 1225)(4200 1275);
WIRE 16 -1 (4200 1275)(4450 1275);
WIRE 16 -1 (4200 1275)(4200 1325);
WIRE 16 -1 (4200 1325)(4450 1325);
WIRE 16 -1 (4200 1325)(4200 1375);
WIRE 16 -1 (4450 1375)(4200 1375);
WIRE 16 -1 (4200 1375)(4200 1425);
WIRE 16 -1 (4200 1425)(4450 1425);
WIRE 16 -1 (4200 1425)(4200 1475);
WIRE 16 -1 (4200 1475)(4450 1475);
WIRE 16 -1 (4200 1475)(4200 1525);
WIRE 16 -1 (4200 1525)(4450 1525);
WIRE 16 -1 (4200 1525)(4200 1575);
WIRE 16 -1 (4200 1575)(4450 1575);
WIRE 16 -1 (4200 1575)(4200 1625);
WIRE 16 -1 (4200 1625)(4450 1625);
WIRE 16 -1 (4200 1625)(4200 1675);
WIRE 16 -1 (4200 1675)(4450 1675);
WIRE 16 -1 (4200 1675)(4200 1725);
WIRE 16 -1 (4200 1725)(4450 1725);
WIRE 16 -1 (4200 1725)(4200 1775);
WIRE 16 -1 (4200 1775)(4450 1775);
WIRE 16 -1 (4200 1775)(4200 1825);
WIRE 16 -1 (4200 1825)(4450 1825);
WIRE 16 -1 (4200 1825)(4200 1875);
WIRE 16 -1 (4450 1875)(4200 1875);
WIRE 16 -1 (4200 1875)(4200 1925);
WIRE 16 -1 (4200 1925)(4450 1925);
WIRE 16 -1 (4200 1925)(4200 1975);
WIRE 16 -1 (4200 1975)(4450 1975);
WIRE 16 -1 (4200 1975)(4200 2025);
WIRE 16 -1 (4200 2025)(4450 2025);
WIRE 16 -1 (4200 2025)(4200 2075);
WIRE 16 -1 (4200 2075)(4450 2075);
WIRE 16 -1 (4200 2075)(4200 2125);
WIRE 16 -1 (4200 2125)(4450 2125);
WIRE 16 -1 (4200 2125)(4200 2175);
WIRE 16 -1 (4200 2175)(4450 2175);
WIRE 16 -1 (4200 2175)(4200 2225);
WIRE 16 -1 (4200 2225)(4450 2225);
WIRE 16 -1 (4200 2225)(4200 2275);
WIRE 16 -1 (4200 2275)(4450 2275);
WIRE 16 -1 (4200 2275)(4200 2325);
WIRE 16 -1 (4200 2325)(4450 2325);
WIRE 16 -1 (4200 2325)(4200 2375);
WIRE 16 -1 (4450 2375)(4200 2375);
WIRE 16 -1 (4200 2375)(4200 2425);
WIRE 16 -1 (4200 2425)(4450 2425);
WIRE 16 -1 (4200 2425)(4200 2475);
WIRE 16 -1 (4200 2475)(4450 2475);
WIRE 16 -1 (4200 2475)(4200 2525);
WIRE 16 -1 (4200 2525)(4450 2525);
WIRE 16 -1 (4200 2525)(4200 2575);
WIRE 16 -1 (4200 2575)(4450 2575);
WIRE 16 -1 (4200 2575)(4200 2625);
WIRE 16 -1 (4200 2625)(4450 2625);
WIRE 16 -1 (4200 2625)(4200 2675);
WIRE 16 -1 (4200 2675)(4450 2675);
WIRE 16 -1 (4200 2675)(4200 2725);
WIRE 16 -1 (4200 2725)(4450 2725);
WIRE 16 -1 (4200 2725)(4200 2775);
WIRE 16 -1 (4200 2775)(4450 2775);
WIRE 16 -1 (4200 2775)(4200 2825);
WIRE 16 -1 (4200 2825)(4450 2825);
WIRE 16 -1 (4200 2825)(4200 2875);
WIRE 16 -1 (4450 2875)(4200 2875);
WIRE 16 -1 (4200 2875)(4200 2925);
WIRE 16 -1 (4200 2925)(4450 2925);
WIRE 16 -1 (4200 2925)(4200 2975);
WIRE 16 -1 (4200 2975)(4450 2975);
WIRE 16 -1 (4200 2975)(4200 3025);
WIRE 16 -1 (4200 3025)(4450 3025);
WIRE 16 -1 (4200 3025)(4200 3075);
WIRE 16 -1 (4200 3075)(4450 3075);
WIRE 16 -1 (4200 3075)(4200 3125);
WIRE 16 -1 (4200 3125)(4450 3125);
WIRE 16 -1 (4200 3125)(4200 3175);
WIRE 16 -1 (4200 3175)(4450 3175);
WIRE 16 -1 (4200 3175)(4200 3225);
WIRE 16 -1 (4200 3225)(4450 3225);
WIRE 16 -1 (4200 3225)(4200 3275);
WIRE 16 -1 (4200 3275)(4450 3275);
WIRE 16 -1 (4200 3275)(4200 3325);
WIRE 16 -1 (4200 3325)(4450 3325);
WIRE 16 -1 (4200 3325)(4200 3375);
WIRE 16 -1 (4450 3375)(4200 3375);
WIRE 16 -1 (4200 3375)(4200 3425);
WIRE 16 -1 (4200 3425)(4450 3425);
WIRE 16 -1 (4200 3425)(4200 3475);
WIRE 16 -1 (4200 3475)(4450 3475);
WIRE 16 -1 (4200 3475)(4200 3525);
WIRE 16 -1 (4200 3525)(4450 3525);
WIRE 16 -1 (4200 3525)(4200 3575);
WIRE 16 -1 (4200 3575)(4450 3575);
WIRE 16 -1 (4200 3575)(4200 3625);
WIRE 16 -1 (4200 3625)(4450 3625);
WIRE 16 -1 (4200 3625)(4200 3675);
WIRE 16 -1 (4200 3675)(4450 3675);
WIRE 16 -1 (4200 3675)(4200 3725);
WIRE 16 -1 (4200 3725)(4450 3725);
WIRE 16 -1 (4200 3725)(4200 3775);
WIRE 16 -1 (4200 3775)(4450 3775);
WIRE 16 -1 (4200 3775)(4200 3825);
WIRE 16 -1 (4200 3825)(4450 3825);
WIRE 16 -1 (4200 3825)(4200 3875);
WIRE 16 -1 (4450 3875)(4200 3875);
WIRE 16 -1 (4200 3875)(4200 3925);
WIRE 16 -1 (4200 3925)(4450 3925);
WIRE 16 -1 (4200 3925)(4200 3975);
WIRE 16 -1 (4450 3975)(4200 3975);
WIRE 16 -1 (5650 4125)(5900 4125);
WIRE 16 -1 (5650 4075)(5900 4075);
WIRE 16 -1 (5900 4125)(5900 4075);
WIRE 16 -1 (5650 4025)(5900 4025);
WIRE 16 -1 (5900 4075)(5900 4025);
WIRE 16 -1 (5650 3975)(5900 3975);
WIRE 16 -1 (5900 4025)(5900 3975);
WIRE 16 -1 (5650 3925)(5900 3925);
WIRE 16 -1 (5900 3975)(5900 3925);
WIRE 16 -1 (5650 3875)(5900 3875);
WIRE 16 -1 (5900 3925)(5900 3875);
WIRE 16 -1 (5650 3825)(5900 3825);
WIRE 16 -1 (5900 3875)(5900 3825);
WIRE 16 -1 (5650 3775)(5900 3775);
WIRE 16 -1 (5900 3825)(5900 3775);
WIRE 16 -1 (5650 3725)(5900 3725);
WIRE 16 -1 (5900 3775)(5900 3725);
WIRE 16 -1 (5650 3675)(5900 3675);
WIRE 16 -1 (5900 3725)(5900 3675);
WIRE 16 -1 (5650 3625)(5900 3625);
WIRE 16 -1 (5900 3675)(5900 3625);
WIRE 16 -1 (5650 3575)(5900 3575);
WIRE 16 -1 (5900 3625)(5900 3575);
WIRE 16 -1 (5650 3525)(5900 3525);
WIRE 16 -1 (5900 3575)(5900 3525);
WIRE 16 -1 (5650 3475)(5900 3475);
WIRE 16 -1 (5900 3525)(5900 3475);
WIRE 16 -1 (5650 3425)(5900 3425);
WIRE 16 -1 (5900 3475)(5900 3425);
WIRE 16 -1 (5650 3375)(5900 3375);
WIRE 16 -1 (5900 3375)(5900 3425);
WIRE 16 -1 (5650 3325)(5900 3325);
WIRE 16 -1 (5900 3375)(5900 3325);
WIRE 16 -1 (5900 3275)(5650 3275);
WIRE 16 -1 (5900 3325)(5900 3275);
WIRE 16 -1 (5900 3225)(5650 3225);
WIRE 16 -1 (5900 3275)(5900 3225);
WIRE 16 -1 (5650 3175)(5900 3175);
WIRE 16 -1 (5900 3225)(5900 3175);
WIRE 16 -1 (5650 3125)(5900 3125);
WIRE 16 -1 (5900 3175)(5900 3125);
WIRE 16 -1 (5650 3075)(5900 3075);
WIRE 16 -1 (5900 3125)(5900 3075);
WIRE 16 -1 (5650 3025)(5900 3025);
WIRE 16 -1 (5900 3075)(5900 3025);
WIRE 16 -1 (5650 2975)(5900 2975);
WIRE 16 -1 (5900 3025)(5900 2975);
WIRE 16 -1 (5650 2925)(5900 2925);
WIRE 16 -1 (5900 2975)(5900 2925);
WIRE 16 -1 (5650 2875)(5900 2875);
WIRE 16 -1 (5900 2875)(5900 2925);
WIRE 16 -1 (5650 2825)(5900 2825);
WIRE 16 -1 (5900 2875)(5900 2825);
WIRE 16 -1 (5900 2775)(5650 2775);
WIRE 16 -1 (5900 2825)(5900 2775);
WIRE 16 -1 (5900 2725)(5650 2725);
WIRE 16 -1 (5900 2775)(5900 2725);
WIRE 16 -1 (5650 2675)(5900 2675);
WIRE 16 -1 (5900 2725)(5900 2675);
WIRE 16 -1 (5650 2625)(5900 2625);
WIRE 16 -1 (5900 2675)(5900 2625);
WIRE 16 -1 (5650 2575)(5900 2575);
WIRE 16 -1 (5900 2625)(5900 2575);
WIRE 16 -1 (5650 2525)(5900 2525);
WIRE 16 -1 (5900 2575)(5900 2525);
WIRE 16 -1 (5650 2475)(5900 2475);
WIRE 16 -1 (5900 2525)(5900 2475);
WIRE 16 -1 (5650 2425)(5900 2425);
WIRE 16 -1 (5900 2475)(5900 2425);
WIRE 16 -1 (5650 2375)(5900 2375);
WIRE 16 -1 (5900 2375)(5900 2425);
WIRE 16 -1 (5650 2325)(5900 2325);
WIRE 16 -1 (5900 2375)(5900 2325);
WIRE 16 -1 (5900 2275)(5650 2275);
WIRE 16 -1 (5900 2325)(5900 2275);
WIRE 16 -1 (5900 2225)(5650 2225);
WIRE 16 -1 (5900 2275)(5900 2225);
WIRE 16 -1 (5650 2175)(5900 2175);
WIRE 16 -1 (5900 2225)(5900 2175);
WIRE 16 -1 (5650 2125)(5900 2125);
WIRE 16 -1 (5900 2175)(5900 2125);
WIRE 16 -1 (5650 2075)(5900 2075);
WIRE 16 -1 (5900 2125)(5900 2075);
WIRE 16 -1 (5650 2025)(5900 2025);
WIRE 16 -1 (5900 2075)(5900 2025);
WIRE 16 -1 (5650 1975)(5900 1975);
WIRE 16 -1 (5900 2025)(5900 1975);
WIRE 16 -1 (5650 1925)(5900 1925);
WIRE 16 -1 (5900 1975)(5900 1925);
WIRE 16 -1 (5650 1875)(5900 1875);
WIRE 16 -1 (5900 1875)(5900 1925);
WIRE 16 -1 (5650 1825)(5900 1825);
WIRE 16 -1 (5900 1875)(5900 1825);
WIRE 16 -1 (5900 1775)(5650 1775);
WIRE 16 -1 (5900 1825)(5900 1775);
WIRE 16 -1 (5900 1725)(5650 1725);
WIRE 16 -1 (5900 1775)(5900 1725);
WIRE 16 -1 (5900 1675)(5650 1675);
WIRE 16 -1 (5900 1725)(5900 1675);
WIRE 16 -1 (5900 1625)(5650 1625);
WIRE 16 -1 (5900 1675)(5900 1625);
WIRE 16 -1 (5650 1575)(5900 1575);
WIRE 16 -1 (5900 1575)(5900 1625);
WIRE 16 -1 (5900 1525)(5650 1525);
WIRE 16 -1 (5900 1525)(5900 1575);
WIRE 16 -1 (5900 1475)(5650 1475);
WIRE 16 -1 (5900 1525)(5900 1475);
WIRE 16 -1 (5900 1425)(5650 1425);
WIRE 16 -1 (5900 1475)(5900 1425);
WIRE 16 -1 (5650 1375)(5900 1375);
WIRE 16 -1 (5900 1425)(5900 1375);
WIRE 16 -1 (5650 1325)(5900 1325);
WIRE 16 -1 (5900 1375)(5900 1325);
WIRE 16 -1 (5650 1275)(5900 1275);
WIRE 16 -1 (5900 1325)(5900 1275);
WIRE 16 -1 (5650 1225)(5900 1225);
WIRE 16 -1 (5900 1275)(5900 1225);
WIRE 16 -1 (5650 1175)(5900 1175);
WIRE 16 -1 (5900 1225)(5900 1175);
WIRE 16 -1 (5650 1125)(5900 1125);
WIRE 16 -1 (5900 1175)(5900 1125);
WIRE 16 -1 (5650 1075)(5900 1075);
WIRE 16 -1 (5900 1125)(5900 1075);
WIRE 16 -1 (5650 1025)(5900 1025);
WIRE 16 -1 (5900 1025)(5900 1075);
WIRE 16 -1 (5650 975)(5900 975);
WIRE 16 -1 (5900 1025)(5900 975);
WIRE 16 -1 (5650 875)(5900 875);
WIRE 16 -1 (5900 975)(5900 875);
WIRE 16 -1 (5900 875)(5900 825);
WIRE 16 -1 (5650 825)(5900 825);
WIRE 16 -1 (-450 2425)(-275 2425);
WIRE 16 -1 (-1650 875)(-2750 875);
FORCEPROP 2 LAST SIG_NAME TP_CHE_CPU0_DIMM2_FRU_0
J 0
(-2662 884);
DISPLAY 0.680851 (-2662 884);
PAINT WHITE (-2662 884);
WIRE 16 -1 (-1650 925)(-2750 925);
FORCEPROP 2 LAST SIG_NAME TP_CHE_CPU0_DIMM2_FRU_1
J 0
(-2662 934);
DISPLAY 0.680851 (-2662 934);
PAINT WHITE (-2662 934);
WIRE 16 -1 (-1650 975)(-2750 975);
FORCEPROP 2 LAST SIG_NAME TP_CHE_CPU0_DIMM2_FRU_2
J 0
(-2662 984);
DISPLAY 0.680851 (-2662 984);
PAINT WHITE (-2662 984);
WIRE 16 -1 (-1650 1025)(-2750 1025);
FORCEPROP 2 LAST SIG_NAME TP_CHE_CPU0_DIMM2_FRU_3
J 0
(-2662 1034);
DISPLAY 0.680851 (-2662 1034);
PAINT WHITE (-2662 1034);
WIRE 16 -1 (-1650 3275)(-2750 3275);
FORCEPROP 2 LAST SIG_NAME M_E_CPU0_SB_PAR
J 0
(-2662 3284);
DISPLAY 0.680851 (-2662 3284);
PAINT WHITE (-2662 3284);
WIRE 16 -1 (-1650 3325)(-2750 3325);
FORCEPROP 2 LAST SIG_NAME M_E_CPU0_SA_PAR
J 0
(-2662 3334);
DISPLAY 0.680851 (-2662 3334);
PAINT WHITE (-2662 3334);
WIRE 16 -1 (-1650 675)(-2750 675);
FORCEPROP 2 LAST SIG_NAME M_E_CPU0_SB_RSP<1>
J 0
(-2662 684);
DISPLAY 0.680851 (-2662 684);
PAINT WHITE (-2662 684);
WIRE 16 -1 (-1650 725)(-2750 725);
FORCEPROP 2 LAST SIG_NAME M_E_CPU0_SA_RSP<1>
J 0
(-2662 734);
DISPLAY 0.680851 (-2662 734);
PAINT WHITE (-2662 734);
WIRE 16 -1 (-450 925)(-275 925);
WIRE 16 -1 (-450 975)(-275 975);
WIRE 16 -1 (-450 1025)(-275 1025);
WIRE 16 -1 (-450 1075)(-275 1075);
WIRE 16 -1 (-450 1125)(-275 1125);
WIRE 16 -1 (-450 1175)(-275 1175);
WIRE 16 -1 (-450 1225)(-275 1225);
WIRE 16 -1 (-450 1275)(-275 1275);
WIRE 16 -1 (-450 1325)(-275 1325);
WIRE 16 -1 (-450 1375)(-275 1375);
WIRE 16 -1 (-450 1425)(-275 1425);
WIRE 16 -1 (-450 1475)(-275 1475);
WIRE 16 -1 (-450 1525)(-275 1525);
WIRE 16 -1 (-450 1575)(-275 1575);
WIRE 16 -1 (-450 1625)(-275 1625);
WIRE 16 -1 (-450 1675)(-275 1675);
WIRE 16 -1 (-450 1725)(-275 1725);
WIRE 16 -1 (-450 1775)(-275 1775);
WIRE 16 -1 (-450 1825)(-275 1825);
WIRE 16 -1 (-450 1875)(-275 1875);
WIRE 16 -1 (-450 1925)(-275 1925);
WIRE 16 -1 (-450 1975)(-275 1975);
WIRE 16 -1 (-450 2075)(-275 2075);
WIRE 16 -1 (-450 2125)(-275 2125);
WIRE 16 -1 (-450 2175)(-275 2175);
WIRE 16 -1 (-450 2225)(-275 2225);
WIRE 16 -1 (-450 2275)(-275 2275);
WIRE 16 -1 (-450 2325)(-275 2325);
WIRE 16 -1 (-450 2375)(-275 2375);
WIRE 16 -1 (-450 2475)(-275 2475);
WIRE 16 -1 (-450 2575)(-275 2575);
WIRE 16 -1 (-450 2625)(-275 2625);
WIRE 16 -1 (-450 2675)(-275 2675);
WIRE 16 -1 (-450 2725)(-275 2725);
WIRE 16 -1 (-450 2825)(-275 2825);
WIRE 16 -1 (-450 2875)(-275 2875);
WIRE 16 -1 (-450 2925)(-275 2925);
WIRE 16 -1 (-450 2975)(-275 2975);
WIRE 16 -1 (-450 3025)(-275 3025);
WIRE 16 -1 (-450 3075)(-275 3075);
WIRE 16 -1 (-450 3125)(-275 3125);
WIRE 16 -1 (-450 3175)(-275 3175);
WIRE 16 -1 (-450 3225)(-275 3225);
WIRE 16 -1 (-450 3275)(-275 3275);
WIRE 16 -1 (-450 3325)(-275 3325);
WIRE 16 -1 (-450 3375)(-275 3375);
WIRE 16 -1 (-450 3425)(-275 3425);
WIRE 16 -1 (-450 3475)(-275 3475);
WIRE 16 -1 (-450 3525)(-275 3525);
WIRE 16 -1 (-450 3575)(-275 3575);
WIRE 16 -1 (-450 3625)(-275 3625);
WIRE 16 -1 (-450 3675)(-275 3675);
WIRE 16 -1 (-450 3725)(-275 3725);
WIRE 16 -1 (-450 3775)(-275 3775);
WIRE 16 -1 (-450 3875)(-275 3875);
WIRE 16 -1 (-450 3925)(-275 3925);
WIRE 16 -1 (-450 3975)(-275 3975);
WIRE 16 -1 (-450 4025)(-275 4025);
WIRE 16 -1 (-450 4075)(-275 4075);
WIRE 16 -1 (-1650 3025)(-2750 3025);
FORCEPROP 2 LAST SIG_NAME M_E_CPU0_SB_CS_N<3>
J 0
(-2662 3034);
DISPLAY 0.680851 (-2662 3034);
PAINT WHITE (-2662 3034);
WIRE 16 -1 (-1650 3175)(-2750 3175);
FORCEPROP 2 LAST SIG_NAME M_E_CPU0_SA_CS_N<3>
J 0
(-2662 3184);
DISPLAY 0.680851 (-2662 3184);
PAINT WHITE (-2662 3184);
WIRE 16 -1 (-1650 2975)(-2750 2975);
FORCEPROP 2 LAST SIG_NAME M_E_CPU0_SB_CS_N<2>
J 0
(-2662 2984);
DISPLAY 0.680851 (-2662 2984);
PAINT WHITE (-2662 2984);
WIRE 16 -1 (-1650 3125)(-2750 3125);
FORCEPROP 2 LAST SIG_NAME M_E_CPU0_SA_CS_N<2>
J 0
(-2662 3134);
DISPLAY 0.680851 (-2662 3134);
PAINT WHITE (-2662 3134);
WIRE 16 -1 (-1650 2875)(-2750 2875);
FORCEPROP 2 LAST SIG_NAME M_E_CPU0_CLK_DP<1>
J 0
(-2662 2884);
DISPLAY 0.680851 (-2662 2884);
PAINT WHITE (-2662 2884);
WIRE 16 -1 (-1650 2825)(-2750 2825);
FORCEPROP 2 LAST SIG_NAME M_E_CPU0_CLK_DN<1>
J 0
(-2662 2834);
DISPLAY 0.680851 (-2662 2834);
PAINT WHITE (-2662 2834);
WIRE 16 -1 (-1825 1925)(-1650 1925);
WIRE 16 -1 (-1825 1975)(-1650 1975);
WIRE 16 -1 (-1825 2025)(-1650 2025);
WIRE 16 -1 (-1825 2075)(-1650 2075);
WIRE 16 -1 (-1825 2125)(-1650 2125);
WIRE 16 -1 (-1825 2175)(-1650 2175);
WIRE 16 -1 (-1825 2225)(-1650 2225);
WIRE 16 -1 (-1825 2475)(-1650 2475);
WIRE 16 -1 (-1825 2525)(-1650 2525);
WIRE 16 -1 (-1825 2625)(-1650 2625);
WIRE 16 -1 (-1825 2675)(-1650 2675);
WIRE 16 -1 (-1825 3725)(-1650 3725);
WIRE 16 -1 (-1825 4125)(-1650 4125);
WIRE 16 -1 (-1825 3675)(-1650 3675);
WIRE 16 -1 (-1825 4075)(-1650 4075);
WIRE 16 -1 (-1825 3625)(-1650 3625);
WIRE 16 -1 (-1825 4025)(-1650 4025);
WIRE 16 -1 (-1825 3575)(-1650 3575);
WIRE 16 -1 (-1825 3975)(-1650 3975);
WIRE 16 -1 (-1825 3525)(-1650 3525);
WIRE 16 -1 (-1825 3925)(-1650 3925);
WIRE 16 -1 (-1825 3475)(-1650 3475);
WIRE 16 -1 (-1825 3875)(-1650 3875);
WIRE 16 -1 (-1825 3425)(-1650 3425);
WIRE 16 -1 (-1825 3825)(-1650 3825);
WIRE 16 -1 (-1825 2275)(-1650 2275);
WIRE 16 -1 (-1825 2425)(-1650 2425);
WIRE 16 -1 (-1825 2575)(-1650 2575);
WIRE 16 -1 (-1825 2725)(-1650 2725);
WIRE 16 -1 (-450 4125)(-275 4125);
WIRE 16 -1 (-1650 175)(-2750 175);
FORCEPROP 2 LAST SIG_NAME PD_CHE_CPU0_DIMM2_SAA
J 0
(-2662 184);
DISPLAY 0.680851 (-2662 184);
PAINT WHITE (-2662 184);
WIRE 16 -1 (-1650 75)(-1650 175);
WIRE 16 -1 (2500 475)(2500 350);
WIRE 16 -1 (3125 475)(2500 475);
WIRE 16 -1 (3125 350)(3125 475);
WIRE 16 -1 (3125 0)(3125 150);
WIRE 16 -1 (3125 0)(2500 0);
WIRE 16 -1 (2500 0)(2500 150);
DOT 1 (4200 3325);
DOT 1 (4200 2925);
DOT 1 (3125 0);
DOT 1 (2500 475);
DOT 1 (4200 875);
DOT 1 (4200 975);
DOT 1 (4200 925);
DOT 1 (4200 1025);
DOT 1 (4200 1075);
DOT 1 (4200 1125);
DOT 1 (4200 1175);
DOT 1 (4200 1225);
DOT 1 (4200 1275);
DOT 1 (4200 1325);
DOT 1 (4200 1375);
DOT 1 (4200 1425);
DOT 1 (4200 1475);
DOT 1 (4200 1525);
DOT 1 (4200 1625);
DOT 1 (4200 1575);
DOT 1 (4200 1675);
DOT 1 (4200 1725);
DOT 1 (4200 1775);
DOT 1 (4200 1825);
DOT 1 (4200 1875);
DOT 1 (4200 1925);
DOT 1 (4200 1975);
DOT 1 (4200 2025);
DOT 1 (5900 975);
DOT 1 (5900 1025);
DOT 1 (5900 1075);
DOT 1 (5900 1175);
DOT 1 (5900 1125);
DOT 1 (5900 1225);
DOT 1 (5900 1275);
DOT 1 (5900 1325);
DOT 1 (5900 1375);
DOT 1 (5900 1425);
DOT 1 (5900 1525);
DOT 1 (5900 1475);
DOT 1 (5900 1575);
DOT 1 (5900 1675);
DOT 1 (5900 1625);
DOT 1 (5900 1725);
DOT 1 (5900 1775);
DOT 1 (5900 1825);
DOT 1 (5900 1875);
DOT 1 (5900 1925);
DOT 1 (5900 1975);
DOT 1 (5900 2025);
DOT 1 (4200 2075);
DOT 1 (4200 2125);
DOT 1 (4200 2175);
DOT 1 (4200 2225);
DOT 1 (4200 2275);
DOT 1 (4200 2325);
DOT 1 (4200 2375);
DOT 1 (4200 2425);
DOT 1 (4200 2475);
DOT 1 (4200 2525);
DOT 1 (4200 2575);
DOT 1 (4200 2625);
DOT 1 (4200 2675);
DOT 1 (4200 2725);
DOT 1 (4200 2775);
DOT 1 (4200 2825);
DOT 1 (4200 2875);
DOT 1 (4200 2975);
DOT 1 (4200 3025);
DOT 1 (4200 3075);
DOT 1 (4200 3125);
DOT 1 (4200 3175);
DOT 1 (4200 3225);
DOT 1 (4200 3275);
DOT 1 (4200 3425);
DOT 1 (4200 3375);
DOT 1 (4200 3475);
DOT 1 (4200 3525);
DOT 1 (4200 3575);
DOT 1 (4200 3625);
DOT 1 (4200 3675);
DOT 1 (4200 3725);
DOT 1 (4200 3775);
DOT 1 (4200 3825);
DOT 1 (4200 3875);
DOT 1 (4200 3925);
DOT 1 (4200 4075);
DOT 1 (5900 2075);
DOT 1 (5900 2125);
DOT 1 (5900 2175);
DOT 1 (5900 2225);
DOT 1 (5900 2325);
DOT 1 (5900 2275);
DOT 1 (5900 2375);
DOT 1 (5900 2425);
DOT 1 (5900 2475);
DOT 1 (5900 2525);
DOT 1 (5900 2575);
DOT 1 (5900 2625);
DOT 1 (5900 2675);
DOT 1 (5900 2725);
DOT 1 (5900 2825);
DOT 1 (5900 2775);
DOT 1 (5900 2875);
DOT 1 (5900 2925);
DOT 1 (5900 2975);
DOT 1 (5900 3025);
DOT 1 (5900 3075);
DOT 1 (5900 3125);
DOT 1 (5900 3225);
DOT 1 (5900 3175);
DOT 1 (5900 3275);
DOT 1 (5900 3325);
DOT 1 (5900 3375);
DOT 1 (5900 3475);
DOT 1 (5900 3425);
DOT 1 (5900 3525);
DOT 1 (5900 3575);
DOT 1 (5900 3625);
DOT 1 (5900 3725);
DOT 1 (5900 3675);
DOT 1 (5900 3775);
DOT 1 (5900 3825);
DOT 1 (5900 3875);
DOT 1 (5900 3975);
DOT 1 (5900 3925);
DOT 1 (5900 4025);
DOT 1 (5900 4075);
DOT 1 (4200 4125);
DOT 1 (5900 875);
DOT 1 (5900 825);
DOT 1 (5900 775);
FORCENOTE
20210728 MODIFY FOR GT
(-3175 4800) 0;
DISPLAY LEFT (-3175 4800);
DISPLAY 2.510638 (-3175 4800);
PAINT PINK (-3175 4800);
QUIT
